%FSTAX25Y25*%
%MOIN*%
%SFA1B1*%

%IPPOS*%
%ADD108C,0.120000*%
%ADD120C,0.075000*%
%ADD121R,0.059060X0.059060*%
%ADD126C,0.016000*%
%LNtimecard-dc-beta-v1-1*%
%LPD*%
G36*
X0708268Y0435313D02*
Y0050513D01*
X0310992*
Y0022539*
X0228992*
Y0031013*
X0225792Y0034213*
X0222992*
X0219792Y0031013*
Y0022539*
X0177692*
Y0046513*
X0173092Y0051113*
X0165892*
X0161392Y0046613*
Y0031299*
X0131692*
Y0050813*
X0057692*
Y0018413*
X0000292*
Y0434938*
X0000668Y0435313*
X0708268*
G37*
%LNtimecard-dc-beta-v1-2*%
%LPC*%
G36*
X0125Y0431749D02*
X0124376Y0431625D01*
X0123846Y0431272*
X0123493Y0430742*
X0123369Y0430118*
X0123493Y0429494*
X0123846Y0428965*
X0124376Y0428611*
X0125Y0428487*
X0125624Y0428611*
X0126154Y0428965*
X0126507Y0429494*
X0126631Y0430118*
X0126507Y0430742*
X0126154Y0431272*
X0125624Y0431625*
X0125Y0431749*
G37*
G36*
X0104331D02*
X0103706Y0431625D01*
X0103177Y0431272*
X0102823Y0430742*
X0102699Y0430118*
X0102823Y0429494*
X0103177Y0428965*
X0103706Y0428611*
X0104331Y0428487*
X0104955Y0428611*
X0105484Y0428965*
X0105838Y0429494*
X0105962Y0430118*
X0105838Y0430742*
X0105484Y0431272*
X0104955Y0431625*
X0104331Y0431749*
G37*
G36*
X0084646D02*
X0084021Y0431625D01*
X0083492Y0431272*
X0083139Y0430742*
X0083014Y0430118*
X0083139Y0429494*
X0083492Y0428965*
X0084021Y0428611*
X0084646Y0428487*
X008527Y0428611*
X0085799Y0428965*
X0086153Y0429494*
X0086277Y0430118*
X0086153Y0430742*
X0085799Y0431272*
X008527Y0431625*
X0084646Y0431749*
G37*
G36*
X0064961D02*
X0064336Y0431625D01*
X0063807Y0431272*
X0063454Y0430742*
X0063329Y0430118*
X0063454Y0429494*
X0063807Y0428965*
X0064336Y0428611*
X0064961Y0428487*
X0065585Y0428611*
X0066114Y0428965*
X0066468Y0429494*
X0066592Y0430118*
X0066468Y0430742*
X0066114Y0431272*
X0065585Y0431625*
X0064961Y0431749*
G37*
G36*
X0543622Y0429966D02*
X0542642Y0429837D01*
X0541729Y0429459*
X0540946Y0428858*
X0540344Y0428074*
X0539966Y0427161*
X0539837Y0426181*
X0539966Y0425201*
X0540344Y0424289*
X0540946Y0423505*
X0541729Y0422903*
X0542642Y0422525*
X0543622Y0422396*
X0544602Y0422525*
X0545515Y0422903*
X0546299Y0423505*
X05469Y0424289*
X0547278Y0425201*
X0547407Y0426181*
X0547278Y0427161*
X05469Y0428074*
X0546299Y0428858*
X0545515Y0429459*
X0544602Y0429837*
X0543622Y0429966*
G37*
G36*
X0533622D02*
X0532642Y0429837D01*
X053173Y0429459*
X0530946Y0428858*
X0530344Y0428074*
X0529966Y0427161*
X0529837Y0426181*
X0529966Y0425201*
X0530344Y0424289*
X0530946Y0423505*
X053173Y0422903*
X0532642Y0422525*
X0533622Y0422396*
X0534602Y0422525*
X0535515Y0422903*
X0536299Y0423505*
X05369Y0424289*
X0537278Y0425201*
X0537407Y0426181*
X0537278Y0427161*
X05369Y0428074*
X0536299Y0428858*
X0535515Y0429459*
X0534602Y0429837*
X0533622Y0429966*
G37*
G36*
X0523622D02*
X0522642Y0429837D01*
X052173Y0429459*
X0520946Y0428858*
X0520344Y0428074*
X0519966Y0427161*
X0519837Y0426181*
X0519966Y0425201*
X0520344Y0424289*
X0520946Y0423505*
X052173Y0422903*
X0522642Y0422525*
X0523622Y0422396*
X0524602Y0422525*
X0525515Y0422903*
X0526299Y0423505*
X05269Y0424289*
X0527278Y0425201*
X0527407Y0426181*
X0527278Y0427161*
X05269Y0428074*
X0526299Y0428858*
X0525515Y0429459*
X0524602Y0429837*
X0523622Y0429966*
G37*
G36*
X0505905Y041797D02*
X0505281Y0417846D01*
X0504752Y0417492*
X0504398Y0416963*
X0504274Y0416339*
X0504398Y0415714*
X0504752Y0415185*
X0505281Y0414831*
X0505905Y0414707*
X050653Y0414831*
X0507059Y0415185*
X0507413Y0415714*
X0507537Y0416339*
X0507413Y0416963*
X0507059Y0417492*
X050653Y0417846*
X0505905Y041797*
G37*
G36*
X0482313Y0430499D02*
X0480618Y0430365D01*
X0478965Y0429969*
X0477395Y0429318*
X0475945Y042843*
X0474653Y0427326*
X0473549Y0426033*
X047266Y0424584*
X047201Y0423013*
X0471613Y042136*
X047148Y0419665*
X0471613Y0417971*
X047201Y0416318*
X047266Y0414747*
X0473549Y0413298*
X0474653Y0412005*
X0475945Y0410901*
X0477395Y0410013*
X0478965Y0409362*
X0480618Y0408965*
X0482313Y0408832*
X0484008Y0408965*
X0485661Y0409362*
X0487231Y0410013*
X0488681Y0410901*
X0489973Y0412005*
X0491077Y0413298*
X0491966Y0414747*
X0492616Y0416318*
X0493013Y0417971*
X0493146Y0419665*
X0493013Y042136*
X0492616Y0423013*
X0491966Y0424584*
X0491077Y0426033*
X0489973Y0427326*
X0488681Y042843*
X0487231Y0429318*
X0485661Y0429969*
X0484008Y0430365*
X0482313Y0430499*
G37*
G36*
X0244124D02*
X0242429Y0430365D01*
X0240776Y0429969*
X0239206Y0429318*
X0237756Y042843*
X0236464Y0427326*
X023536Y0426033*
X0234471Y0424584*
X0233821Y0423013*
X0233424Y042136*
X0233291Y0419665*
X0233424Y0417971*
X0233821Y0416318*
X0234471Y0414747*
X023536Y0413298*
X0236464Y0412005*
X0237756Y0410901*
X0239206Y0410013*
X0240776Y0409362*
X0242429Y0408965*
X0244124Y0408832*
X0245819Y0408965*
X0247472Y0409362*
X0249042Y0410013*
X0250492Y0410901*
X0251784Y0412005*
X0252888Y0413298*
X0253777Y0414747*
X0254427Y0416318*
X0254824Y0417971*
X0254957Y0419665*
X0254824Y042136*
X0254427Y0423013*
X0253777Y0424584*
X0252888Y0426033*
X0251784Y0427326*
X0250492Y042843*
X0249042Y0429318*
X0247472Y0429969*
X0245819Y0430365*
X0244124Y0430499*
G37*
G36*
X0181102Y041108D02*
X0180478Y0410956D01*
X0179949Y0410602*
X0179595Y0410073*
X0179471Y0409449*
X0179595Y0408824*
X0179949Y0408295*
X0180478Y0407942*
X0181102Y0407818*
X0181727Y0407942*
X0182256Y0408295*
X0182609Y0408824*
X0182734Y0409449*
X0182609Y0410073*
X0182256Y0410602*
X0181727Y0410956*
X0181102Y041108*
G37*
G36*
X0173228D02*
X0172604Y0410956D01*
X0172075Y0410602*
X0171721Y0410073*
X0171597Y0409449*
X0171721Y0408824*
X0172075Y0408295*
X0172604Y0407942*
X0173228Y0407818*
X0173853Y0407942*
X0174382Y0408295*
X0174735Y0408824*
X017486Y0409449*
X0174735Y0410073*
X0174382Y0410602*
X0173853Y0410956*
X0173228Y041108*
G37*
G36*
X019661Y0412745D02*
X019554Y0412604D01*
X0194543Y0412191*
X0193687Y0411534*
X019303Y0410677*
X0192616Y040968*
X0192476Y040861*
X0192616Y040754*
X019303Y0406543*
X0193687Y0405687*
X0194543Y040503*
X019554Y0404616*
X019661Y0404476*
X019768Y0404616*
X0198678Y040503*
X0199534Y0405687*
X0200191Y0406543*
X0200604Y040754*
X0200745Y040861*
X0200604Y040968*
X0200191Y0410677*
X0199534Y0411534*
X0198678Y0412191*
X019768Y0412604*
X019661Y0412745*
G37*
G36*
X016661D02*
X016554Y0412604D01*
X0164543Y0412191*
X0163687Y0411534*
X016303Y0410677*
X0162617Y040968*
X0162476Y040861*
X0162617Y040754*
X016303Y0406543*
X0163687Y0405687*
X0164543Y040503*
X016554Y0404616*
X016661Y0404476*
X016768Y0404616*
X0168677Y040503*
X0169534Y0405687*
X0170191Y0406543*
X0170604Y040754*
X0170745Y040861*
X0170604Y040968*
X0170191Y0410677*
X0169534Y0411534*
X0168677Y0412191*
X016768Y0412604*
X016661Y0412745*
G37*
G36*
X0028543Y0428547D02*
X0026456Y0428383D01*
X0024421Y0427894*
X0022487Y0427093*
X0020702Y0425999*
X001911Y042464*
X001775Y0423048*
X0016656Y0421263*
X0015855Y0419329*
X0015366Y0417293*
X0015202Y0415206*
X0015366Y0413119*
X0015855Y0411084*
X0016656Y040915*
X001775Y0407365*
X001911Y0405773*
X0020702Y0404413*
X0022487Y0403319*
X0024421Y0402518*
X0026456Y0402029*
X0028543Y0401865*
X003063Y0402029*
X0032666Y0402518*
X00346Y0403319*
X0036385Y0404413*
X0037977Y0405773*
X0039336Y0407365*
X004043Y040915*
X0041232Y0411084*
X004172Y0413119*
X0041884Y0415206*
X004172Y0417293*
X0041232Y0419329*
X004043Y0421263*
X0039336Y0423048*
X0037977Y042464*
X0036385Y0425999*
X00346Y0427093*
X0032666Y0427894*
X003063Y0428383*
X0028543Y0428547*
G37*
G36*
X0124397Y0403225D02*
X0123773Y0403101D01*
X0123243Y0402747*
X012289Y0402218*
X0122766Y0401594*
X012289Y0400969*
X0123243Y040044*
X0123773Y0400086*
X0124397Y0399962*
X0125021Y0400086*
X012555Y040044*
X0125904Y0400969*
X0126028Y0401594*
X0125904Y0402218*
X012555Y0402747*
X0125021Y0403101*
X0124397Y0403225*
G37*
G36*
X010423Y0403092D02*
X0103606Y0402968D01*
X0103077Y0402614*
X0102723Y0402085*
X0102599Y040146*
X0102723Y0400836*
X0103077Y0400307*
X0103606Y0399953*
X010423Y0399829*
X0104855Y0399953*
X0105384Y0400307*
X0105737Y0400836*
X0105861Y040146*
X0105737Y0402085*
X0105384Y0402614*
X0104855Y0402968*
X010423Y0403092*
G37*
G36*
X0084064Y0402958D02*
X0083439Y0402834D01*
X008291Y0402481*
X0082556Y0401951*
X0082432Y0401327*
X0082556Y0400703*
X008291Y0400174*
X0083439Y039982*
X0084064Y0399696*
X0084688Y039982*
X0085217Y0400174*
X0085571Y0400703*
X0085695Y0401327*
X0085571Y0401951*
X0085217Y0402481*
X0084688Y0402834*
X0084064Y0402958*
G37*
G36*
X0063897Y0402925D02*
X0063273Y0402801D01*
X0062743Y0402447*
X006239Y0401918*
X0062265Y0401294*
X006239Y0400669*
X0062743Y040014*
X0063273Y0399786*
X0063897Y0399662*
X0064521Y0399786*
X006505Y040014*
X0065404Y0400669*
X0065528Y0401294*
X0065404Y0401918*
X006505Y0402447*
X0064521Y0402801*
X0063897Y0402925*
G37*
G36*
X021752Y036482D02*
X0216895Y0364696D01*
X0216366Y0364342*
X0216013Y0363813*
X0215888Y0363189*
X0216013Y0362565*
X0216366Y0362035*
X0216895Y0361682*
X021752Y0361558*
X0218144Y0361682*
X0218673Y0362035*
X0219027Y0362565*
X0219151Y0363189*
X0219027Y0363813*
X0218673Y0364342*
X0218144Y0364696*
X021752Y036482*
G37*
G36*
X0199803D02*
X0199179Y0364696D01*
X019865Y0364342*
X0198296Y0363813*
X0198172Y0363189*
X0198296Y0362565*
X019865Y0362035*
X0199179Y0361682*
X0199803Y0361558*
X0200427Y0361682*
X0200957Y0362035*
X020131Y0362565*
X0201434Y0363189*
X020131Y0363813*
X0200957Y0364342*
X0200427Y0364696*
X0199803Y036482*
G37*
G36*
X0181794Y0364528D02*
X018117Y0364404D01*
X0180641Y036405*
X0180287Y0363521*
X0180163Y0362897*
X0180287Y0362273*
X0180641Y0361743*
X018117Y036139*
X0181794Y0361265*
X0182419Y036139*
X0182948Y0361743*
X0183302Y0362273*
X0183426Y0362897*
X0183302Y0363521*
X0182948Y036405*
X0182419Y0364404*
X0181794Y0364528*
G37*
G36*
X0163992Y0364442D02*
X0163368Y0364318D01*
X0162839Y0363965*
X0162485Y0363435*
X0162361Y0362811*
X0162485Y0362187*
X0162839Y0361658*
X0163368Y0361304*
X0163992Y036118*
X0164616Y0361304*
X0165146Y0361658*
X0165499Y0362187*
X0165623Y0362811*
X0165499Y0363435*
X0165146Y0363965*
X0164616Y0364318*
X0163992Y0364442*
G37*
G36*
X0238189Y0363836D02*
X0237565Y0363712D01*
X0237035Y0363358*
X0236682Y0362829*
X0236558Y0362205*
X0236682Y036158*
X0237035Y0361051*
X0237565Y0360698*
X0238189Y0360573*
X0238813Y0360698*
X0239342Y0361051*
X0239696Y036158*
X023982Y0362205*
X0239696Y0362829*
X0239342Y0363358*
X0238813Y0363712*
X0238189Y0363836*
G37*
G36*
X025503Y0360609D02*
X0254134Y0360431D01*
X0253374Y0359923*
X0252867Y0359164*
X0252689Y0358268*
X0252867Y0357372*
X0253374Y0356612*
X0254134Y0356105*
X025503Y0355927*
X0255925Y0356105*
X0256685Y0356612*
X0257192Y0357372*
X0257371Y0358268*
X0257192Y0359164*
X0256685Y0359923*
X0255925Y0360431*
X025503Y0360609*
G37*
G36*
X0271654Y0355962D02*
X0271029Y0355838D01*
X02705Y0355484*
X0270146Y0354955*
X0270022Y0354331*
X0270146Y0353706*
X02705Y0353177*
X0271029Y0352823*
X0271654Y0352699*
X0272278Y0352823*
X0272807Y0353177*
X0273161Y0353706*
X0273285Y0354331*
X0273161Y0354955*
X0272807Y0355484*
X0272278Y0355838*
X0271654Y0355962*
G37*
G36*
X0238189D02*
X0237565Y0355838D01*
X0237035Y0355484*
X0236682Y0354955*
X0236558Y0354331*
X0236682Y0353706*
X0237035Y0353177*
X0237565Y0352823*
X0238189Y0352699*
X0238813Y0352823*
X0239342Y0353177*
X0239696Y0353706*
X023982Y0354331*
X0239696Y0354955*
X0239342Y0355484*
X0238813Y0355838*
X0238189Y0355962*
G37*
G36*
X0271654Y0348088D02*
X0271029Y0347964D01*
X02705Y034761*
X0270146Y0347081*
X0270022Y0346457*
X0270146Y0345832*
X02705Y0345303*
X0271029Y034495*
X0271654Y0344825*
X0272278Y034495*
X0272807Y0345303*
X0273161Y0345832*
X0273285Y0346457*
X0273161Y0347081*
X0272807Y034761*
X0272278Y0347964*
X0271654Y0348088*
G37*
G36*
X0238189D02*
X0237565Y0347964D01*
X0237035Y034761*
X0236682Y0347081*
X0236558Y0346457*
X0236682Y0345832*
X0237035Y0345303*
X0237565Y034495*
X0238189Y0344825*
X0238813Y034495*
X0239342Y0345303*
X0239696Y0345832*
X023982Y0346457*
X0239696Y0347081*
X0239342Y034761*
X0238813Y0347964*
X0238189Y0348088*
G37*
G36*
X025503Y0344861D02*
X0254134Y0344683D01*
X0253374Y0344175*
X0252867Y0343416*
X0252689Y034252*
X0252867Y0341624*
X0253374Y0340864*
X0254134Y0340357*
X025503Y0340179*
X0255925Y0340357*
X0256685Y0340864*
X0257192Y0341624*
X0257371Y034252*
X0257192Y0343416*
X0256685Y0344175*
X0255925Y0344683*
X025503Y0344861*
G37*
G36*
X0304134Y0341198D02*
X030351Y0341074D01*
X030298Y0340721*
X0302627Y0340191*
X0302502Y0339567*
X0302627Y0338943*
X030298Y0338413*
X030351Y033806*
X0304134Y0337936*
X0304758Y033806*
X0305287Y0338413*
X0305641Y0338943*
X0305765Y0339567*
X0305641Y0340191*
X0305287Y0340721*
X0304758Y0341074*
X0304134Y0341198*
G37*
G36*
X0276772Y032171D02*
X0276147Y0321586D01*
X0275618Y0321232*
X0275265Y0320703*
X027514Y0320079*
X0275265Y0319454*
X0275618Y0318925*
X0276147Y0318572*
X0276772Y0318447*
X0277396Y0318572*
X0277925Y0318925*
X0278279Y0319454*
X0278403Y0320079*
X0278279Y0320703*
X0277925Y0321232*
X0277396Y0321586*
X0276772Y032171*
G37*
G36*
X0667108Y0317614D02*
X0666484Y031749D01*
X0666124Y0317249*
X0665764Y031749*
X066514Y0317614*
X0664515Y031749*
X0664155Y0317249*
X0663796Y031749*
X0663171Y0317614*
X0662547Y031749*
X0662018Y0317136*
X0661664Y0316607*
X066154Y0315982*
X0661664Y0315358*
X0661905Y0314998*
X0661664Y0314638*
X066154Y0314014*
X0661664Y0313389*
X0662018Y031286*
X0662547Y0312507*
X0663171Y0312382*
X0663796Y0312507*
X0664155Y0312747*
X0664515Y0312507*
X066514Y0312382*
X0665764Y0312507*
X0666124Y0312747*
X0666484Y0312507*
X0667108Y0312382*
X0667733Y0312507*
X0668262Y031286*
X0668615Y0313389*
X066874Y0314014*
X0668615Y0314638*
X0668375Y0314998*
X0668615Y0315358*
X066874Y0315982*
X0668615Y0316607*
X0668262Y0317136*
X0667733Y031749*
X0667108Y0317614*
G37*
G36*
X0482313Y0328136D02*
X0480618Y0328003D01*
X0478965Y0327606*
X0477395Y0326956*
X0475945Y0326067*
X0474653Y0324963*
X0473549Y0323671*
X047266Y0322221*
X047201Y0320651*
X0471613Y0318998*
X047148Y0317303*
X0471613Y0315608*
X047201Y0313955*
X047266Y0312385*
X0473549Y0310935*
X0474653Y0309643*
X0475945Y0308539*
X0477395Y030765*
X0478965Y0307*
X0480618Y0306603*
X0482313Y030647*
X0484008Y0306603*
X0485661Y0307*
X0487231Y030765*
X0488681Y0308539*
X0489973Y0309643*
X0491077Y0310935*
X0491966Y0312385*
X0492616Y0313955*
X0493013Y0315608*
X0493146Y0317303*
X0493013Y0318998*
X0492616Y0320651*
X0491966Y0322221*
X0491077Y0323671*
X0489973Y0324963*
X0488681Y0326067*
X0487231Y0326956*
X0485661Y0327606*
X0484008Y0328003*
X0482313Y0328136*
G37*
G36*
X0244124D02*
X0242429Y0328003D01*
X0240776Y0327606*
X0239206Y0326956*
X0237756Y0326067*
X0236464Y0324963*
X023536Y0323671*
X0234471Y0322221*
X0233821Y0320651*
X0233424Y0318998*
X0233291Y0317303*
X0233424Y0315608*
X0233821Y0313955*
X0234471Y0312385*
X023536Y0310935*
X0236464Y0309643*
X0237756Y0308539*
X0239206Y030765*
X0240776Y0307*
X0242429Y0306603*
X0244124Y030647*
X0245819Y0306603*
X0247472Y0307*
X0249042Y030765*
X0250492Y0308539*
X0251784Y0309643*
X0252888Y0310935*
X0253777Y0312385*
X0254427Y0313955*
X0254824Y0315608*
X0254957Y0317303*
X0254824Y0318998*
X0254427Y0320651*
X0253777Y0322221*
X0252888Y0323671*
X0251784Y0324963*
X0250492Y0326067*
X0249042Y0326956*
X0247472Y0327606*
X0245819Y0328003*
X0244124Y0328136*
G37*
G36*
X0350394Y0304749D02*
X0349769Y0304625D01*
X034924Y0304272*
X0348886Y0303742*
X0348762Y0303118*
X0348886Y0302494*
X034924Y0301965*
X0349769Y0301611*
X0350394Y0301487*
X0351018Y0301611*
X0351547Y0301965*
X0351901Y0302494*
X0352025Y0303118*
X0351901Y0303742*
X0351547Y0304272*
X0351018Y0304625*
X0350394Y0304749*
G37*
G36*
X0525591Y029986D02*
X0524966Y0299735D01*
X0524437Y0299382*
X0524083Y0298853*
X0523959Y0298228*
X0524083Y0297604*
X0524437Y0297075*
X0524966Y0296721*
X0525591Y0296597*
X0526215Y0296721*
X0526744Y0297075*
X0527098Y0297604*
X0527222Y0298228*
X0527098Y0298853*
X0526744Y0299382*
X0526215Y0299735*
X0525591Y029986*
G37*
G36*
X05Y0296907D02*
X0499376Y0296783D01*
X0498846Y0296429*
X0498493Y02959*
X0498369Y0295276*
X0498493Y0294651*
X0498846Y0294122*
X0499376Y0293768*
X05Y0293644*
X0500624Y0293768*
X0501154Y0294122*
X0501507Y0294651*
X0501631Y0295276*
X0501507Y02959*
X0501154Y0296429*
X0500624Y0296783*
X05Y0296907*
G37*
G36*
X0320866Y0294938D02*
X0320242Y0294814D01*
X0319713Y0294461*
X0319359Y0293931*
X0319235Y0293307*
X0319359Y0292683*
X0319713Y0292154*
X0320242Y02918*
X0320866Y0291676*
X032149Y02918*
X032202Y0292154*
X0322373Y0292683*
X0322498Y0293307*
X0322373Y0293931*
X032202Y0294461*
X032149Y0294814*
X0320866Y0294938*
G37*
G36*
X0324803Y0294907D02*
X0324179Y0294783D01*
X032365Y0294429*
X0323296Y02939*
X0323172Y0293276*
X0323296Y0292651*
X032365Y0292122*
X0324179Y0291768*
X0324803Y0291644*
X0325427Y0291768*
X0325957Y0292122*
X032631Y0292651*
X0326434Y0293276*
X032631Y02939*
X0325957Y0294429*
X0325427Y0294783*
X0324803Y0294907*
G37*
G36*
X0329918Y0293994D02*
X0329294Y0293869D01*
X0328764Y0293516*
X0328411Y0292986*
X0328287Y0292362*
X0328411Y0291738*
X0328764Y0291209*
X0329294Y0290855*
X0329918Y0290731*
X0330542Y0290855*
X0331071Y0291209*
X0331425Y0291738*
X0331549Y0292362*
X0331425Y0292986*
X0331071Y0293516*
X0330542Y0293869*
X0329918Y0293994*
G37*
G36*
X030115Y0292938D02*
X0300525Y0292814D01*
X0299996Y0292461*
X0299642Y0291931*
X0299518Y0291307*
X0299642Y0290683*
X0299996Y0290154*
X0300525Y02898*
X030115Y0289676*
X0301774Y02898*
X0302303Y0290154*
X0302657Y0290683*
X0302781Y0291307*
X0302657Y0291931*
X0302303Y0292461*
X0301774Y0292814*
X030115Y0292938*
G37*
G36*
X0294341Y0292921D02*
X0293716Y0292796D01*
X0293187Y0292443*
X0292833Y0291914*
X0292709Y0291289*
X0292833Y0290665*
X0293187Y0290136*
X0293716Y0289782*
X0294341Y0289658*
X0294965Y0289782*
X0295494Y0290136*
X0295848Y0290665*
X0295972Y0291289*
X0295848Y0291914*
X0295494Y0292443*
X0294965Y0292796*
X0294341Y0292921*
G37*
G36*
X0564921Y0292025D02*
X0564297Y0291901D01*
X0563768Y0291547*
X0563414Y0291018*
X056329Y0290394*
X0563414Y0289769*
X0563768Y028924*
X0564297Y0288886*
X0564921Y0288762*
X0565546Y0288886*
X0566075Y028924*
X0566428Y0289769*
X0566553Y0290394*
X0566428Y0291018*
X0566075Y0291547*
X0565546Y0291901*
X0564921Y0292025*
G37*
G36*
X0371477Y0291248D02*
X0370852Y0291123D01*
X0370323Y029077*
X0369969Y029024*
X0369845Y0289616*
X0369969Y0288992*
X0370323Y0288463*
X0370852Y0288109*
X0371477Y0287985*
X0372101Y0288109*
X037263Y0288463*
X0372984Y0288992*
X0373108Y0289616*
X0372984Y029024*
X037263Y029077*
X0372101Y0291123*
X0371477Y0291248*
G37*
G36*
X0449803Y0291001D02*
X0449179Y0290877D01*
X044865Y0290524*
X0448296Y0289994*
X0448172Y028937*
X0448296Y0288746*
X044865Y0288216*
X0449179Y0287863*
X0449803Y0287739*
X0450427Y0287863*
X0450957Y0288216*
X045131Y0288746*
X0451435Y028937*
X045131Y0289994*
X0450957Y0290524*
X0450427Y0290877*
X0449803Y0291001*
G37*
G36*
X0570866Y0287064D02*
X0570242Y028694D01*
X0569713Y0286587*
X0569359Y0286057*
X0569235Y0285433*
X0569359Y0284809*
X0569713Y0284279*
X0570242Y0283926*
X0570866Y0283802*
X057149Y0283926*
X057202Y0284279*
X0572373Y0284809*
X0572498Y0285433*
X0572373Y0286057*
X057202Y0286587*
X057149Y028694*
X0570866Y0287064*
G37*
G36*
X0449803Y028608D02*
X0449179Y0285956D01*
X044865Y0285602*
X0448296Y0285073*
X0448172Y0284449*
X0448296Y0283824*
X044865Y0283295*
X0449179Y0282942*
X0449803Y0282818*
X0450427Y0282942*
X0450957Y0283295*
X045131Y0283824*
X0451435Y0284449*
X045131Y0285073*
X0450957Y0285602*
X0450427Y0285956*
X0449803Y028608*
G37*
G36*
X0249938Y0285158D02*
X0249313Y0285034D01*
X0248784Y028468*
X0248431Y0284151*
X0248306Y0283527*
X0248431Y0282902*
X0248784Y0282373*
X0249313Y028202*
X0249938Y0281895*
X0250562Y028202*
X0251091Y0282373*
X0251445Y0282902*
X0251569Y0283527*
X0251445Y0284151*
X0251091Y028468*
X0250562Y0285034*
X0249938Y0285158*
G37*
G36*
X0523228Y0283127D02*
X0522604Y0283003D01*
X0522075Y028265*
X0521721Y028212*
X0521597Y0281496*
X0521721Y0280872*
X0522075Y0280343*
X0522604Y0279989*
X0523228Y0279865*
X0523853Y0279989*
X0524382Y0280343*
X0524735Y0280872*
X052486Y0281496*
X0524735Y028212*
X0524382Y028265*
X0523853Y0283003*
X0523228Y0283127*
G37*
G36*
X0564961Y0282143D02*
X0564336Y0282019D01*
X0563807Y0281665*
X0563453Y0281136*
X0563329Y0280512*
X0563453Y0279888*
X0563807Y0279358*
X0564336Y0279005*
X0564961Y0278881*
X0565585Y0279005*
X0566114Y0279358*
X0566468Y0279888*
X0566592Y0280512*
X0566468Y0281136*
X0566114Y0281665*
X0565585Y0282019*
X0564961Y0282143*
G37*
G36*
X0362205Y0283127D02*
X036158Y0283003D01*
X0361051Y028265*
X0360698Y028212*
X0360573Y0281496*
X0360698Y0280872*
X0361051Y0280343*
X0361099Y0280311*
Y0279811*
X0361002Y0279746*
X0360648Y0279217*
X0360524Y0278592*
X0360648Y0277968*
X0361002Y0277439*
X0361531Y0277085*
X0362156Y0276961*
X036278Y0277085*
X0363309Y0277439*
X0363663Y0277968*
X0363787Y0278592*
X0363663Y0279217*
X0363309Y0279746*
X0363262Y0279778*
Y0280278*
X0363358Y0280343*
X0363712Y0280872*
X0363836Y0281496*
X0363712Y028212*
X0363358Y028265*
X0362829Y0283003*
X0362205Y0283127*
G37*
G36*
X0343504Y0277222D02*
X034288Y0277098D01*
X034235Y0276744*
X0341997Y0276215*
X0341873Y027559*
X0341997Y0274966*
X034235Y0274437*
X034288Y0274083*
X0343504Y0273959*
X0344128Y0274083*
X0344657Y0274437*
X0345011Y0274966*
X0345135Y027559*
X0345011Y0276215*
X0344657Y0276744*
X0344128Y0277098*
X0343504Y0277222*
G37*
G36*
X0564921Y0277183D02*
X0564297Y0277058D01*
X0563768Y0276705*
X0563414Y0276175*
X056329Y0275551*
X0563414Y0274927*
X0563768Y0274398*
X0564297Y0274044*
X0564921Y027392*
X0565546Y0274044*
X0566075Y0274398*
X0566428Y0274927*
X0566553Y0275551*
X0566428Y0276175*
X0566075Y0276705*
X0565546Y0277058*
X0564921Y0277183*
G37*
G36*
X0492913Y0276434D02*
X0492289Y027631D01*
X049176Y0275957*
X0491406Y0275427*
X0491282Y0274803*
X0491406Y0274179*
X049176Y027365*
X0492289Y0273296*
X0492913Y0273172*
X0493538Y0273296*
X0494067Y027365*
X0494421Y0274179*
X0494545Y0274803*
X0494421Y0275427*
X0494067Y0275957*
X0493538Y027631*
X0492913Y0276434*
G37*
G36*
X0312894Y0275352D02*
X0312269Y0275228D01*
X031174Y0274874*
X0311386Y0274345*
X0311262Y0273721*
X0311386Y0273096*
X031174Y0272567*
X0312269Y0272213*
X0312894Y0272089*
X0313518Y0272213*
X0314047Y0272567*
X0314401Y0273096*
X0314525Y0273721*
X0314401Y0274345*
X0314047Y0274874*
X0313518Y0275228*
X0312894Y0275352*
G37*
G36*
X0523228Y0275253D02*
X0522604Y0275129D01*
X0522075Y0274776*
X0521721Y0274246*
X0521597Y0273622*
X0521721Y0272998*
X0522075Y0272468*
X0522604Y0272115*
X0523228Y0271991*
X0523853Y0272115*
X0524382Y0272468*
X0524735Y0272998*
X052486Y0273622*
X0524735Y0274246*
X0524382Y0274776*
X0523853Y0275129*
X0523228Y0275253*
G37*
G36*
X024311Y0269379D02*
X0242486Y0269255D01*
X0241957Y0268902*
X0241603Y0268372*
X0241479Y0267748*
X0241603Y0267124*
X0241957Y0266595*
X0242486Y0266241*
X024311Y0266117*
X0243735Y0266241*
X0244264Y0266595*
X0244617Y0267124*
X0244742Y0267748*
X0244617Y0268372*
X0244264Y0268902*
X0243735Y0269255*
X024311Y0269379*
G37*
G36*
X0237205Y0269348D02*
X023658Y0269224D01*
X0236051Y026887*
X0235698Y0268341*
X0235573Y0267717*
X0235698Y0267092*
X0236051Y0266563*
X023658Y0266209*
X0237205Y0266085*
X0237829Y0266209*
X0238358Y0266563*
X0238712Y0267092*
X0238836Y0267717*
X0238712Y0268341*
X0238358Y026887*
X0237829Y0269224*
X0237205Y0269348*
G37*
G36*
X0247638Y0261868D02*
X0247013Y0261743D01*
X0246484Y026139*
X0246035*
X0245506Y0261743*
X0244882Y0261868*
X0244258Y0261743*
X0243728Y026139*
X0243375Y026086*
X024325Y0260236*
X0243375Y0259612*
X0243728Y0259083*
X0244258Y0258729*
X0244882Y0258605*
X0245506Y0258729*
X0246035Y0259083*
X0246484*
X0247013Y0258729*
X0247638Y0258605*
X0248262Y0258729*
X0248791Y0259083*
X0249145Y0259612*
X0249269Y0260236*
X0249145Y026086*
X0248791Y026139*
X0248262Y0261743*
X0247638Y0261868*
G37*
G36*
X0258858Y0264427D02*
X0258234Y0264302D01*
X0257705Y0263949*
X0257351Y026342*
X0257227Y0262795*
X0257351Y0262171*
X0257705Y0261642*
X0258234Y0261288*
X0258858Y0261164*
X0259483Y0261288*
X0260012Y0261642*
X0260365Y0262171*
X026049Y0262795*
X0260365Y026342*
X0260012Y0263949*
X0259483Y0264302*
X0258858Y0264427*
G37*
G36*
X0290059Y0262261D02*
X0289435Y0262137D01*
X0288906Y0261784*
X0288552Y0261254*
X0288428Y026063*
X0288552Y0260006*
X0288906Y0259476*
X0289435Y0259123*
X0290059Y0258999*
X0290683Y0259123*
X0291213Y0259476*
X0291566Y0260006*
X029169Y026063*
X0291566Y0261254*
X0291213Y0261784*
X0290683Y0262137*
X0290059Y0262261*
G37*
G36*
X0298031Y0262163D02*
X0297407Y0262039D01*
X0296878Y0261685*
X0296524Y0261156*
X02964Y0260531*
X0296524Y0259907*
X0296878Y0259378*
X0297407Y0259024*
X0298031Y02589*
X0298656Y0259024*
X0299185Y0259378*
X0299539Y0259907*
X0299663Y0260531*
X0299539Y0261156*
X0299185Y0261685*
X0298656Y0262039*
X0298031Y0262163*
G37*
G36*
X0228051Y0261671D02*
X0227427Y0261546D01*
X0226898Y0261193*
X0226544Y0260664*
X022642Y0260039*
X0226544Y0259415*
X0226898Y0258886*
X0227427Y0258532*
X0228051Y0258408*
X0228676Y0258532*
X0229205Y0258886*
X0229558Y0259415*
X0229682Y0260039*
X0229558Y0260664*
X0229205Y0261193*
X0228676Y0261546*
X0228051Y0261671*
G37*
G36*
X0293069Y0259614D02*
X0292444Y025949D01*
X0291915Y0259136*
X0291561Y0258607*
X0291437Y0257983*
X0291561Y0257358*
X0291915Y0256829*
X0292444Y0256475*
X0293069Y0256351*
X0293693Y0256475*
X0294222Y0256829*
X0294576Y0257358*
X02947Y0257983*
X0294576Y0258607*
X0294222Y0259136*
X0293693Y025949*
X0293069Y0259614*
G37*
G36*
X0430778Y0263054D02*
X042959Y0262897D01*
X0428483Y0262439*
X0427532Y026171*
X0426803Y0260759*
X0426345Y0259652*
X0426188Y0258465*
X0426345Y0257277*
X0426803Y025617*
X0427532Y025522*
X0428483Y025449*
X042959Y0254032*
X0430778Y0253875*
X0431965Y0254032*
X0433072Y025449*
X0434023Y025522*
X0434752Y025617*
X043521Y0257277*
X0435367Y0258465*
X043521Y0259652*
X0434752Y0260759*
X0434023Y026171*
X0433072Y0262439*
X0431965Y0262897*
X0430778Y0263054*
G37*
G36*
X0418966D02*
X0417779Y0262897D01*
X0416672Y0262439*
X0415721Y026171*
X0414992Y0260759*
X0414534Y0259652*
X0414377Y0258465*
X0414534Y0257277*
X0414992Y025617*
X0415721Y025522*
X0416672Y025449*
X0417779Y0254032*
X0418966Y0253875*
X0420154Y0254032*
X0421261Y025449*
X0422212Y025522*
X0422941Y025617*
X0423399Y0257277*
X0423556Y0258465*
X0423399Y0259652*
X0422941Y0260759*
X0422212Y026171*
X0421261Y0262439*
X0420154Y0262897*
X0418966Y0263054*
G37*
G36*
X0407156D02*
X0405968Y0262897D01*
X0404861Y0262439*
X040391Y026171*
X0403181Y0260759*
X0402723Y0259652*
X0402566Y0258465*
X0402723Y0257277*
X0403181Y025617*
X040391Y025522*
X0404861Y025449*
X0405968Y0254032*
X0407156Y0253875*
X0408343Y0254032*
X040945Y025449*
X0410401Y025522*
X041113Y025617*
X0411588Y0257277*
X0411745Y0258465*
X0411588Y0259652*
X041113Y0260759*
X0410401Y026171*
X040945Y0262439*
X0408343Y0262897*
X0407156Y0263054*
G37*
G36*
X011998Y0251828D02*
X0119356Y0251704D01*
X0118827Y025135*
X0118473Y0250821*
X0118349Y0250197*
X0118473Y0249573*
X0118827Y0249043*
X0119356Y024869*
X011998Y0248566*
X0120605Y024869*
X0121134Y0249043*
X0121487Y0249573*
X0121612Y0250197*
X0121487Y0250821*
X0121134Y025135*
X0120605Y0251704*
X011998Y0251828*
G37*
G36*
X0619685Y0250872D02*
X0618749Y0250686D01*
X0617955Y0250155*
X0617424Y0249362*
X0617238Y0248425*
X0617424Y0247489*
X0617955Y0246695*
X0618749Y0246164*
X0619685Y0245978*
X0620621Y0246164*
X0621415Y0246695*
X0621946Y0247489*
X0622132Y0248425*
X0621946Y0249362*
X0621415Y0250155*
X0620621Y0250686*
X0619685Y0250872*
G37*
G36*
X055873Y0252424D02*
X0557543Y0252268D01*
X0556436Y0251809*
X0555485Y025108*
X0554756Y0250129*
X0554297Y0249022*
X0554141Y0247835*
X0554297Y0246647*
X0554756Y024554*
X0555485Y024459*
X0556436Y024386*
X0557543Y0243402*
X055873Y0243245*
X0559918Y0243402*
X0561025Y024386*
X0561975Y024459*
X0562705Y024554*
X0563163Y0246647*
X0563319Y0247835*
X0563163Y0249022*
X0562705Y0250129*
X0561975Y025108*
X0561025Y0251809*
X0559918Y0252268*
X055873Y0252424*
G37*
G36*
X0299014Y0245759D02*
X029828Y0245613D01*
X0297657Y0245197*
X0297241Y0244574*
X0297095Y024384*
X0297241Y0243105*
X0297657Y0242482*
X029828Y0242066*
X0299014Y024192*
X0299749Y0242066*
X0300372Y0242482*
X0300788Y0243105*
X0300934Y024384*
X0300788Y0244574*
X0300372Y0245197*
X0299749Y0245613*
X0299014Y0245759*
G37*
G36*
X0220274D02*
X021954Y0245613D01*
X0218917Y0245197*
X0218501Y0244574*
X0218355Y024384*
X0218501Y0243105*
X0218917Y0242482*
X021954Y0242066*
X0220274Y024192*
X0221009Y0242066*
X0221632Y0242482*
X0222048Y0243105*
X0222194Y024384*
X0222048Y0244574*
X0221632Y0245197*
X0221009Y0245613*
X0220274Y0245759*
G37*
G36*
X0361755Y0255353D02*
X0360441Y0255224D01*
X0359177Y0254841*
X0358012Y0254218*
X0356991Y025338*
X0356153Y0252359*
X035553Y0251194*
X0355147Y024993*
X0355017Y0248616*
X0355147Y0247301*
X035553Y0246037*
X0356153Y0244872*
X0356991Y0243851*
X0358012Y0243013*
X0359177Y024239*
X0360441Y0242007*
X0361755Y0241878*
X036307Y0242007*
X0364334Y024239*
X0365499Y0243013*
X036652Y0243851*
X0367358Y0244872*
X0367981Y0246037*
X0368364Y0247301*
X0368493Y0248616*
X0368364Y024993*
X0367981Y0251194*
X0367358Y0252359*
X036652Y025338*
X0365499Y0254218*
X0364334Y0254841*
X036307Y0255224*
X0361755Y0255353*
G37*
G36*
X0165155D02*
X0163841Y0255224D01*
X0162577Y0254841*
X0161412Y0254218*
X0160391Y025338*
X0159553Y0252359*
X015893Y0251194*
X0158547Y024993*
X0158417Y0248616*
X0158547Y0247301*
X015893Y0246037*
X0159553Y0244872*
X0160391Y0243851*
X0161412Y0243013*
X0162577Y024239*
X0163841Y0242007*
X0165155Y0241878*
X016647Y0242007*
X0167734Y024239*
X0168899Y0243013*
X016992Y0243851*
X0170758Y0244872*
X017138Y0246037*
X0171764Y0247301*
X0171893Y0248616*
X0171764Y024993*
X017138Y0251194*
X0170758Y0252359*
X016992Y025338*
X0168899Y0254218*
X0167734Y0254841*
X016647Y0255224*
X0165155Y0255353*
G37*
G36*
X0019984Y0254537D02*
X001873Y0254414D01*
X0017523Y0254048*
X0016411Y0253453*
X0015437Y0252654*
X0014637Y0251679*
X0014043Y0250567*
X0013677Y0249361*
X0013553Y0248106*
X0013677Y0246852*
X0014043Y0245645*
X0014637Y0244533*
X0015437Y0243559*
X0016411Y0242759*
X0017523Y0242165*
X001873Y0241799*
X0019984Y0241675*
X0021239Y0241799*
X0022445Y0242165*
X0023557Y0242759*
X0024532Y0243559*
X0025331Y0244533*
X0025926Y0245645*
X0026292Y0246852*
X0026415Y0248106*
X0026292Y0249361*
X0025926Y0250567*
X0025331Y0251679*
X0024532Y0252654*
X0023557Y0253453*
X0022445Y0254048*
X0021239Y0254414*
X0019984Y0254537*
G37*
G36*
X0166437Y0235293D02*
X0165813Y0235169D01*
X0165284Y0234815*
X016493Y0234286*
X0164806Y0233661*
X016493Y0233037*
X0165284Y0232508*
X0165813Y0232154*
X0166437Y023203*
X0167061Y0232154*
X0167591Y0232508*
X0167944Y0233037*
X0168068Y0233661*
X0167944Y0234286*
X0167591Y0234815*
X0167061Y0235169*
X0166437Y0235293*
G37*
G36*
X0233563Y0230667D02*
X0232939Y0230543D01*
X0232651Y023035*
X0232283Y023023*
X0231916Y023035*
X0231628Y0230543*
X0231004Y0230667*
X023038Y0230543*
X022985Y0230189*
X0229497Y022966*
X0229373Y0229035*
X0229497Y0228411*
X022985Y0227882*
X023038Y0227528*
X0231004Y0227404*
X0231628Y0227528*
X0231916Y022772*
X0232283Y0227841*
X0232651Y022772*
X0232939Y0227528*
X0233563Y0227404*
X0234187Y0227528*
X0234717Y0227882*
X023507Y0228411*
X0235194Y0229035*
X023507Y022966*
X0234717Y0230189*
X0234187Y0230543*
X0233563Y0230667*
G37*
G36*
X0262598Y0230765D02*
X0261974Y0230641D01*
X0261445Y0230287*
X0261341Y0230131*
X0260739*
X0260701Y0230189*
X0260172Y0230543*
X0259547Y0230667*
X0258923Y0230543*
X0258394Y0230189*
X025804Y022966*
X0257991Y0229413*
X0257481*
X0257413Y0229758*
X0257059Y0230287*
X025653Y0230641*
X0255906Y0230765*
X0255281Y0230641*
X0254752Y0230287*
X0254679Y0230178*
X0254179*
X0254106Y0230287*
X0253577Y0230641*
X0252953Y0230765*
X0252328Y0230641*
X0251799Y0230287*
X0251446Y0229758*
X0251321Y0229134*
X0251446Y022851*
X0251799Y022798*
X0252328Y0227627*
X0252953Y0227502*
X0253577Y0227627*
X0254106Y022798*
X0254179Y0228089*
X0254679*
X0254752Y022798*
X0255281Y0227627*
X0255906Y0227502*
X025653Y0227627*
X0257059Y022798*
X0257413Y022851*
X0257462Y0228756*
X0257972*
X025804Y0228411*
X0258394Y0227882*
X0258923Y0227528*
X0259547Y0227404*
X0260172Y0227528*
X0260701Y0227882*
X0260805Y0228038*
X0261406*
X0261445Y022798*
X0261974Y0227627*
X0262598Y0227502*
X0263223Y0227627*
X0263752Y022798*
X0264106Y022851*
X026423Y0229134*
X0264106Y0229758*
X0263752Y0230287*
X0263223Y0230641*
X0262598Y0230765*
G37*
G36*
X0107283Y0232931D02*
X0106659Y0232806D01*
X010613Y0232453*
X0105776Y0231924*
X0105652Y0231299*
X0105776Y0230675*
X010613Y0230146*
X0106659Y0229792*
X0107283Y0229668*
X0107908Y0229792*
X0108437Y0230146*
X0108791Y0230675*
X0108915Y0231299*
X0108791Y0231924*
X0108437Y0232453*
X0107908Y0232806*
X0107283Y0232931*
G37*
G36*
X0164961Y0231651D02*
X0164336Y0231527D01*
X0163807Y0231173*
X0163453Y0230644*
X0163329Y023002*
X0163453Y0229395*
X0163807Y0228866*
X0164336Y0228513*
X0164961Y0228388*
X0165585Y0228513*
X0166114Y0228866*
X0166468Y0229395*
X0166592Y023002*
X0166468Y0230644*
X0166114Y0231173*
X0165585Y0231527*
X0164961Y0231651*
G37*
G36*
X0280512Y0230962D02*
X0279888Y0230838D01*
X0279358Y0230484*
X0279005Y0229955*
X0278881Y0229331*
X0279005Y0228706*
X0279358Y0228177*
X0279888Y0227823*
X0280512Y0227699*
X0281136Y0227823*
X0281665Y0228177*
X0282019Y0228706*
X0282143Y0229331*
X0282019Y0229955*
X0281665Y0230484*
X0281136Y0230838*
X0280512Y0230962*
G37*
G36*
X0272638D02*
X0272013Y0230838D01*
X0271484Y0230484*
X0271131Y0229955*
X0271006Y0229331*
X0271131Y0228706*
X0271484Y0228177*
X0272013Y0227823*
X0272638Y0227699*
X0273262Y0227823*
X0273791Y0228177*
X0274145Y0228706*
X0274269Y0229331*
X0274145Y0229955*
X0273791Y0230484*
X0273262Y0230838*
X0272638Y0230962*
G37*
G36*
X029813Y0230864D02*
X0297506Y0230739D01*
X0296976Y0230386*
X0296623Y0229857*
X0296499Y0229232*
X0296623Y0228608*
X0296976Y0228079*
X0297506Y0227725*
X029813Y0227601*
X0298754Y0227725*
X0299284Y0228079*
X0299637Y0228608*
X0299761Y0229232*
X0299637Y0229857*
X0299284Y0230386*
X0298754Y0230739*
X029813Y0230864*
G37*
G36*
X0286024D02*
X0285399Y0230739D01*
X028487Y0230386*
X0284516Y0229857*
X0284392Y0229232*
X0284516Y0228608*
X028487Y0228079*
X0285399Y0227725*
X0286024Y0227601*
X0286648Y0227725*
X0287177Y0228079*
X0287531Y0228608*
X0287655Y0229232*
X0287531Y0229857*
X0287177Y0230386*
X0286648Y0230739*
X0286024Y0230864*
G37*
G36*
X0266437Y0230765D02*
X0265813Y0230641D01*
X0265283Y0230287*
X026493Y0229758*
X0264806Y0229134*
X026493Y022851*
X0265283Y022798*
X0265813Y0227627*
X0266437Y0227502*
X0267061Y0227627*
X026759Y022798*
X0267944Y022851*
X0268068Y0229134*
X0267944Y0229758*
X026759Y0230287*
X0267061Y0230641*
X0266437Y0230765*
G37*
G36*
X0240613Y02309D02*
X0239989Y0230776D01*
X023946Y0230422*
X0239106Y0229893*
X0238982Y0229269*
X0239106Y0228644*
X023946Y0228115*
X0239989Y0227761*
X0240613Y0227637*
X0241238Y0227761*
X0241556Y0227974*
X0242099Y022798*
X024224Y0227923*
X0242683Y0227627*
X0243307Y0227502*
X0243931Y0227627*
X0244319Y0227886*
X0244521Y0227585*
X024505Y0227231*
X0245674Y0227107*
X0246299Y0227231*
X0246828Y0227585*
X0247049Y0227916*
X0247483Y0227627*
X0248107Y0227502*
X0248731Y0227627*
X0249261Y022798*
X0249614Y022851*
X0249738Y0229134*
X0249614Y0229758*
X0249261Y0230287*
X0248731Y0230641*
X0248107Y0230765*
X0247483Y0230641*
X0246954Y0230287*
X0246732Y0229956*
X0246299Y0230245*
X0245674Y023037*
X024505Y0230245*
X0244662Y0229986*
X0244461Y0230287*
X0243931Y0230641*
X0243307Y0230765*
X0242683Y0230641*
X0242307Y023039*
X0241767Y0230422*
X0241238Y0230776*
X0240613Y02309*
G37*
G36*
X004626Y0228994D02*
X0045636Y0228869D01*
X0045106Y0228516*
X0044753Y0227987*
X0044629Y0227362*
X0044753Y0226738*
X0045106Y0226209*
X0045636Y0225855*
X004626Y0225731*
X0046884Y0225855*
X0047413Y0226209*
X0047767Y0226738*
X0047891Y0227362*
X0047767Y0227987*
X0047413Y0228516*
X0046884Y0228869*
X004626Y0228994*
G37*
G36*
X0293307Y0219151D02*
X0292683Y0219027D01*
X0292154Y0218673*
X0291893Y0218283*
X0291818Y0218261*
X0291412*
X0291337Y0218283*
X0291076Y0218673*
X0290547Y0219027*
X0289923Y0219151*
X0289299Y0219027*
X0288769Y0218673*
X0288416Y0218144*
X0288292Y021752*
X0288416Y0216895*
X0288769Y0216366*
X0289299Y0216013*
X0289923Y0215888*
X0290547Y0216013*
X0291076Y0216366*
X0291337Y0216757*
X0291412Y0216779*
X0291818*
X0291893Y0216757*
X0292154Y0216366*
X0292683Y0216013*
X0293307Y0215888*
X0293931Y0216013*
X0294461Y0216366*
X0294814Y0216895*
X0294938Y021752*
X0294814Y0218144*
X0294461Y0218673*
X0293931Y0219027*
X0293307Y0219151*
G37*
G36*
X0169644Y0211629D02*
X016891Y0211483D01*
X0168287Y0211067*
X0167871Y0210444*
X0167725Y020971*
X0167871Y0208975*
X0168287Y0208352*
X016891Y0207936*
X0169644Y020779*
X0170379Y0207936*
X0171002Y0208352*
X0171418Y0208975*
X0171564Y020971*
X0171418Y0210444*
X0171002Y0211067*
X0170379Y0211483*
X0169644Y0211629*
G37*
G36*
X0357136Y0211625D02*
X0356401Y0211479D01*
X0355778Y0211063*
X0355362Y021044*
X0355216Y0209705*
X0355362Y0208971*
X0355778Y0208348*
X0356401Y0207932*
X0357136Y0207786*
X035787Y0207932*
X0358493Y0208348*
X0358909Y0208971*
X0359055Y0209705*
X0358909Y021044*
X0358493Y0211063*
X035787Y0211479*
X0357136Y0211625*
G37*
G36*
X065748Y0210293D02*
X0656856Y0210169D01*
X0656327Y0209815*
X0655973Y0209286*
X0655849Y0208661*
X0655973Y0208037*
X0656327Y0207508*
X0656856Y0207154*
X065748Y020703*
X0658105Y0207154*
X0658634Y0207508*
X0658988Y0208037*
X0659112Y0208661*
X0658988Y0209286*
X0658634Y0209815*
X0658105Y0210169*
X065748Y0210293*
G37*
G36*
X0184144Y0211779D02*
X0183519Y0211655D01*
X018299Y0211301*
X0182637Y0210772*
X0182512Y0210148*
X0182637Y0209523*
X018299Y0208994*
X0183071Y0208453*
X0182922Y0208228*
X0182797Y0207604*
X0182922Y020698*
X0183275Y0206451*
X0183805Y0206097*
X0184429Y0205973*
X0185053Y0206097*
X0185582Y0206451*
X0185936Y020698*
X018606Y0207604*
X0185936Y0208228*
X0185582Y0208758*
X0185467Y0208835*
X0185297Y0208994*
X0185651Y0209523*
X0185775Y0210148*
X0185651Y0210772*
X0185297Y0211301*
X0184768Y0211655*
X0184144Y0211779*
G37*
G36*
X0622047Y0208324D02*
X0621423Y02082D01*
X0620894Y0207846*
X062054Y0207317*
X0620416Y0206693*
X062054Y0206069*
X0620894Y0205539*
X0621423Y0205186*
X0622047Y0205062*
X0622672Y0205186*
X0623201Y0205539*
X0623554Y0206069*
X0623679Y0206693*
X0623554Y0207317*
X0623201Y0207846*
X0622672Y02082*
X0622047Y0208324*
G37*
G36*
Y0202419D02*
X0621423Y0202295D01*
X0621063Y0202054*
X0620703Y0202295*
X0620079Y0202419*
X0619454Y0202295*
X0618925Y0201941*
X0618572Y0201412*
X0618447Y0200787*
X0618572Y0200163*
X0618812Y0199803*
X0618572Y0199443*
X0618447Y0198819*
X0618572Y0198195*
X0618812Y0197835*
X0618572Y0197475*
X0618447Y019685*
X0618572Y0196226*
X0618925Y0195697*
X0619454Y0195343*
X0620079Y0195219*
X0620703Y0195343*
X0621063Y0195584*
X0621423Y0195343*
X0622047Y0195219*
X0622672Y0195343*
X0623201Y0195697*
X0623554Y0196226*
X0623679Y019685*
X0623554Y0197475*
X0623314Y0197835*
X0623554Y0198195*
X0623679Y0198819*
X0623554Y0199443*
X0623314Y0199803*
X0623554Y0200163*
X0623679Y0200787*
X0623554Y0201412*
X0623201Y0201941*
X0622672Y0202295*
X0622047Y0202419*
G37*
G36*
X0373031Y0210293D02*
X0372407Y0210169D01*
X0371878Y0209815*
X0371524Y0209286*
X03714Y0208661*
X0371524Y0208037*
X0371765Y0207677*
X0371524Y0207317*
X03714Y0206693*
X0371524Y0206069*
X0371765Y0205709*
X0371524Y0205349*
X03714Y0204724*
X0371524Y02041*
X0371765Y020374*
X0371524Y020338*
X03714Y0202756*
X0371524Y0202132*
X0371878Y0201602*
X0372407Y0201249*
X0373031Y0201125*
X0373656Y0201249*
X0374185Y0201602*
X0374539Y0202132*
X0374663Y0202756*
X0374539Y020338*
X0374298Y020374*
X0374539Y02041*
X0374663Y0204724*
X0374539Y0205349*
X0374298Y0205709*
X0374539Y0206069*
X0374663Y0206693*
X0374539Y0207317*
X0374298Y0207677*
X0374539Y0208037*
X0374663Y0208661*
X0374539Y0209286*
X0374185Y0209815*
X0373656Y0210169*
X0373031Y0210293*
G37*
G36*
X0338583D02*
X0337958Y0210169D01*
X0337429Y0209815*
X0337075Y0209286*
X0336951Y0208661*
X0337075Y0208037*
X0337316Y0207677*
X0337075Y0207317*
X0336951Y0206693*
X0337075Y0206069*
X0337316Y0205709*
X0337075Y0205349*
X0336951Y0204724*
X0337075Y02041*
X0337316Y020374*
X0337075Y020338*
X0336951Y0202756*
X0337075Y0202132*
X0337429Y0201602*
X0337958Y0201249*
X0338583Y0201125*
X0339207Y0201249*
X0339736Y0201602*
X034009Y0202132*
X0340214Y0202756*
X034009Y020338*
X0339849Y020374*
X034009Y02041*
X0340214Y0204724*
X034009Y0205349*
X0339849Y0205709*
X034009Y0206069*
X0340214Y0206693*
X034009Y0207317*
X0339849Y0207677*
X034009Y0208037*
X0340214Y0208661*
X034009Y0209286*
X0339736Y0209815*
X0339207Y0210169*
X0338583Y0210293*
G37*
G36*
X0119685Y0198383D02*
X0119061Y0198259D01*
X0118532Y0197906*
X0118178Y0197376*
X0118054Y0196752*
X0118178Y0196128*
X0118532Y0195598*
X0119061Y0195245*
X0119685Y0195121*
X0120309Y0195245*
X0120839Y0195598*
X0121192Y0196128*
X0121316Y0196752*
X0121192Y0197376*
X0120839Y0197906*
X0120309Y0198259*
X0119685Y0198383*
G37*
G36*
X0019984Y0202037D02*
X001873Y0201914D01*
X0017523Y0201548*
X0016411Y0200954*
X0015437Y0200154*
X0014637Y0199179*
X0014043Y0198067*
X0013677Y0196861*
X0013553Y0195606*
X0013677Y0194352*
X0014043Y0193145*
X0014637Y0192033*
X0015437Y0191059*
X0016411Y0190259*
X0017523Y0189665*
X001873Y0189299*
X0019984Y0189175*
X0021239Y0189299*
X0022445Y0189665*
X0023557Y0190259*
X0024532Y0191059*
X0025331Y0192033*
X0025926Y0193145*
X0026292Y0194352*
X0026415Y0195606*
X0026292Y0196861*
X0025926Y0198067*
X0025331Y0199179*
X0024532Y0200154*
X0023557Y0200954*
X0022445Y0201548*
X0021239Y0201914*
X0019984Y0202037*
G37*
G36*
X0373031Y0190608D02*
X0372407Y0190483D01*
X0371878Y019013*
X0371524Y0189601*
X03714Y0188976*
X0371524Y0188352*
X0371878Y0187823*
X0372407Y0187469*
X0373031Y0187345*
X0373656Y0187469*
X0374185Y0187823*
X0374539Y0188352*
X0374663Y0188976*
X0374539Y0189601*
X0374185Y019013*
X0373656Y0190483*
X0373031Y0190608*
G37*
G36*
X0386371Y0179781D02*
X0385747Y0179657D01*
X0385218Y0179303*
X0384864Y0178774*
X038474Y017815*
X0384864Y0177525*
X0385218Y0176996*
X0385747Y0176642*
X0386371Y0176518*
X0386996Y0176642*
X0387525Y0176996*
X0387878Y0177525*
X0388003Y017815*
X0387878Y0178774*
X0387525Y0179303*
X0386996Y0179657*
X0386371Y0179781*
G37*
G36*
X0373031Y0181749D02*
X0372407Y0181625D01*
X0371878Y0181272*
X0371524Y0180742*
X03714Y0180118*
X0371524Y0179494*
X0371878Y0178965*
X0371987Y0178892*
Y0178392*
X0371878Y0178319*
X0371524Y017779*
X03714Y0177165*
X0371524Y0176541*
X0371878Y0176012*
X0372407Y0175658*
X0373031Y0175534*
X0373656Y0175658*
X0374185Y0176012*
X0374539Y0176541*
X0374663Y0177165*
X0374539Y017779*
X0374185Y0178319*
X0374076Y0178392*
Y0178892*
X0374185Y0178965*
X0374539Y0179494*
X0374663Y0180118*
X0374539Y0180742*
X0374185Y0181272*
X0373656Y0181625*
X0373031Y0181749*
G37*
G36*
X0107283Y0178797D02*
X0106659Y0178673D01*
X010613Y0178319*
X0105776Y017779*
X0105652Y0177165*
X0105776Y0176541*
X010613Y0176012*
X0106659Y0175658*
X0107283Y0175534*
X0107908Y0175658*
X0108437Y0176012*
X0108791Y0176541*
X0108915Y0177165*
X0108791Y017779*
X0108437Y0178319*
X0107908Y0178673*
X0107283Y0178797*
G37*
G36*
X0401575Y0179781D02*
X040095Y0179657D01*
X0400421Y0179303*
X0400068Y0178774*
X0399943Y017815*
X0400068Y0177525*
X0400196Y0177332*
X0400305Y0176814*
X0400153Y0176574*
X0399954Y0176276*
X0399829Y0175652*
X0399954Y0175027*
X0400307Y0174498*
X0400837Y0174144*
X0401461Y017402*
X0402085Y0174144*
X0402614Y0174498*
X0402968Y0175027*
X0403092Y0175652*
X0402968Y0176276*
X0402839Y0176469*
X040273Y0176987*
X0402883Y0177227*
X0403082Y0177525*
X0403206Y017815*
X0403082Y0178774*
X0402728Y0179303*
X0402199Y0179657*
X0401575Y0179781*
G37*
G36*
X0107283Y0170923D02*
X0106659Y0170799D01*
X010613Y0170445*
X0105776Y0169916*
X0105652Y0169291*
X0105776Y0168667*
X010613Y0168138*
X0106659Y0167784*
X0107283Y016766*
X0107908Y0167784*
X0108437Y0168138*
X0108791Y0168667*
X0108915Y0169291*
X0108791Y0169916*
X0108437Y0170445*
X0107908Y0170799*
X0107283Y0170923*
G37*
G36*
X0373031Y0168923D02*
X0372407Y0168798D01*
X0371878Y0168445*
X0371524Y0167916*
X03714Y0167291*
X0371524Y0166667*
X0371878Y0166138*
X0372407Y0165784*
X0373031Y016566*
X0373656Y0165784*
X0374185Y0166138*
X0374539Y0166667*
X0374663Y0167291*
X0374539Y0167916*
X0374185Y0168445*
X0373656Y0168798*
X0373031Y0168923*
G37*
G36*
X0331802Y0168583D02*
X0331178Y0168459D01*
X0330649Y0168105*
X0330295Y0167576*
X0330171Y0166952*
X0330295Y0166327*
X0330649Y0165798*
X0331178Y0165444*
X0331802Y016532*
X0332427Y0165444*
X0332956Y0165798*
X033331Y0166327*
X0333434Y0166952*
X033331Y0167576*
X0332956Y0168105*
X0332427Y0168459*
X0331802Y0168583*
G37*
G36*
X0683858Y0167408D02*
X0682922Y0167221D01*
X0682128Y0166691*
X0681598Y0165897*
X0681411Y0164961*
X0681598Y0164024*
X0682128Y016323*
X0682922Y01627*
X0683858Y0162514*
X0684795Y01627*
X0685589Y016323*
X0686119Y0164024*
X0686305Y0164961*
X0686119Y0165897*
X0685589Y0166691*
X0684795Y0167221*
X0683858Y0167408*
G37*
G36*
X0386372Y0165098D02*
X0385748Y0164973D01*
X0385218Y016462*
X0384865Y0164091*
X038474Y0163466*
X0384865Y0162842*
X0385082Y0162516*
X0385201Y0162232*
X0385106Y0161787*
X0384925Y0161517*
X0384801Y0160893*
X0384925Y0160268*
X0385279Y0159739*
X038544Y0159632*
Y015903*
X0385304Y015894*
X038495Y0158411*
X0384826Y0157787*
X038495Y0157162*
X0385304Y0156633*
X0385833Y0156279*
X0386458Y0156155*
X0387082Y0156279*
X0387611Y0156633*
X0387965Y0157162*
X0388089Y0157787*
X0387965Y0158411*
X0387611Y015894*
X0387451Y0159047*
Y0159649*
X0387586Y0159739*
X038794Y0160268*
X0388064Y0160893*
X038794Y0161517*
X0387722Y0161843*
X0387603Y0162127*
X0387699Y0162572*
X0387879Y0162842*
X0388003Y0163466*
X0387879Y0164091*
X0387525Y016462*
X0386996Y0164973*
X0386372Y0165098*
G37*
G36*
X0401575Y0166986D02*
X040095Y0166861D01*
X0400421Y0166508*
X0400068Y0165979*
X0399943Y0165354*
X0400068Y016473*
X0400421Y0164201*
Y0163987*
X0400068Y0163457*
X0399943Y0162833*
X0400068Y0162209*
X0400421Y0161679*
Y0161587*
X0400068Y0161057*
X0399943Y0160433*
X0400068Y0159809*
X0400421Y015928*
X040053Y0159207*
Y0158707*
X0400421Y0158634*
X0400068Y0158105*
X0399943Y015748*
X0400068Y0156856*
X0400421Y0156327*
X040095Y0155973*
X0401575Y0155849*
X0402199Y0155973*
X0402728Y0156327*
X0403082Y0156856*
X0403206Y015748*
X0403082Y0158105*
X0402728Y0158634*
X0402619Y0158707*
Y0159207*
X0402728Y015928*
X0403082Y0159809*
X0403206Y0160433*
X0403082Y0161057*
X0402728Y0161587*
Y0161679*
X0403082Y0162209*
X0403206Y0162833*
X0403082Y0163457*
X0402728Y0163987*
Y0164201*
X0403082Y016473*
X0403206Y0165354*
X0403082Y0165979*
X0402728Y0166508*
X0402199Y0166861*
X0401575Y0166986*
G37*
G36*
X0188944Y0153238D02*
X018832Y0153114D01*
X0187791Y015276*
X0187437Y0152231*
X0187313Y0151607*
X0187437Y0150982*
X0187791Y0150453*
X018832Y01501*
X0188944Y0149975*
X0189569Y01501*
X0190098Y0150453*
X0190452Y0150982*
X0190576Y0151607*
X0190452Y0152231*
X0190098Y015276*
X0189569Y0153114*
X0188944Y0153238*
G37*
G36*
X0149606Y0153206D02*
X0148982Y0153082D01*
X0148453Y0152728*
X0148099Y0152199*
X0147975Y0151575*
X0148099Y0150951*
X0148453Y0150421*
X0148982Y0150068*
X0149606Y0149943*
X0150231Y0150068*
X015076Y0150421*
X0151113Y0150951*
X0151238Y0151575*
X0151113Y0152199*
X015076Y0152728*
X0150231Y0153082*
X0149606Y0153206*
G37*
G36*
X0134843D02*
X0134218Y0153082D01*
X0133689Y0152728*
X0133335Y0152199*
X0133211Y0151575*
X0133335Y0150951*
X0133689Y0150421*
X0134218Y0150068*
X0134843Y0149943*
X0135467Y0150068*
X0135996Y0150421*
X013635Y0150951*
X0136474Y0151575*
X013635Y0152199*
X0135996Y0152728*
X0135467Y0153082*
X0134843Y0153206*
G37*
G36*
X0597441Y0147301D02*
X0596817Y0147177D01*
X0596457Y0146936*
X0596097Y0147177*
X0595472Y0147301*
X0594848Y0147177*
X0594319Y0146823*
X0593965Y0146294*
X0593841Y0145669*
X0593965Y0145045*
X0594206Y0144685*
X0593965Y0144325*
X0593841Y0143701*
X0593965Y0143077*
X0594206Y0142717*
X0593965Y0142357*
X0593841Y0141732*
X0593965Y0141108*
X0594319Y0140579*
X0594848Y0140225*
X0595472Y0140101*
X0596097Y0140225*
X0596457Y0140466*
X0596817Y0140225*
X0597441Y0140101*
X0598065Y0140225*
X0598595Y0140579*
X0598948Y0141108*
X0599072Y0141732*
X0598948Y0142357*
X0598708Y0142717*
X0598948Y0143077*
X0599072Y0143701*
X0598948Y0144325*
X0598708Y0144685*
X0598948Y0145045*
X0599072Y0145669*
X0598948Y0146294*
X0598595Y0146823*
X0598065Y0147177*
X0597441Y0147301*
G37*
G36*
X011939Y0145135D02*
X0118765Y0145011D01*
X0118236Y0144658*
X0117883Y0144128*
X0117758Y0143504*
X0117883Y014288*
X0118236Y014235*
X0118765Y0141997*
X011939Y0141873*
X0120014Y0141997*
X0120543Y014235*
X0120897Y014288*
X0121021Y0143504*
X0120897Y0144128*
X0120543Y0144658*
X0120014Y0145011*
X011939Y0145135*
G37*
G36*
X0019984Y0149537D02*
X001873Y0149414D01*
X0017523Y0149048*
X0016411Y0148453*
X0015437Y0147654*
X0014637Y0146679*
X0014043Y0145567*
X0013677Y0144361*
X0013553Y0143106*
X0013677Y0141852*
X0014043Y0140645*
X0014637Y0139533*
X0015437Y0138559*
X0016411Y0137759*
X0017523Y0137165*
X001873Y0136799*
X0019984Y0136675*
X0021239Y0136799*
X0022445Y0137165*
X0023557Y0137759*
X0024532Y0138559*
X0025331Y0139533*
X0025926Y0140645*
X0026292Y0141852*
X0026415Y0143106*
X0026292Y0144361*
X0025926Y0145567*
X0025331Y0146679*
X0024532Y0147654*
X0023557Y0148453*
X0022445Y0149048*
X0021239Y0149414*
X0019984Y0149537*
G37*
G36*
X0341142Y0144053D02*
X0340517Y0143928D01*
X0339988Y0143575*
X0339635Y0143046*
X033951Y0142421*
X0339635Y0141797*
X0339988Y0141268*
X0340169Y0141147*
Y0140546*
X0339988Y0140425*
X0339635Y0139896*
X033951Y0139272*
X0339635Y0138647*
X0339988Y0138118*
X0340095Y0138047*
X034013Y0137468*
X0339776Y0136939*
X0339652Y0136314*
X0339776Y013569*
X034013Y0135161*
X0340244Y0135084*
Y0135071*
X033989Y0134541*
X0339766Y0133917*
X033989Y0133293*
X0340244Y0132764*
X0340773Y013241*
X0341397Y0132286*
X0342022Y013241*
X0342551Y0132764*
X0342905Y0133293*
X0343029Y0133917*
X0342905Y0134541*
X0342551Y0135071*
X0342437Y0135147*
Y0135161*
X034279Y013569*
X0342915Y0136314*
X034279Y0136939*
X0342437Y0137468*
X0342329Y013754*
X0342295Y0138118*
X0342649Y0138647*
X0342773Y0139272*
X0342649Y0139896*
X0342295Y0140425*
X0342115Y0140546*
Y0141147*
X0342295Y0141268*
X0342649Y0141797*
X0342773Y0142421*
X0342649Y0143046*
X0342295Y0143575*
X0341766Y0143928*
X0341142Y0144053*
G37*
G36*
X0169644Y0132889D02*
X016891Y0132743D01*
X0168287Y0132327*
X0167871Y0131704*
X0167725Y013097*
X0167871Y0130235*
X0168287Y0129612*
X016891Y0129196*
X0169644Y012905*
X0170379Y0129196*
X0171002Y0129612*
X0171418Y0130235*
X0171564Y013097*
X0171418Y0131704*
X0171002Y0132327*
X0170379Y0132743*
X0169644Y0132889*
G37*
G36*
X0357136Y0132885D02*
X0356401Y0132739D01*
X0355778Y0132323*
X0355362Y01317*
X0355216Y0130965*
X0355362Y0130231*
X0355778Y0129608*
X0356401Y0129192*
X0357136Y0129046*
X035787Y0129192*
X0358493Y0129608*
X0358909Y0130231*
X0359055Y0130965*
X0358909Y01317*
X0358493Y0132323*
X035787Y0132739*
X0357136Y0132885*
G37*
G36*
X0045276Y0122694D02*
X0044651Y012257D01*
X0044122Y0122216*
X0043768Y0121687*
X0043644Y0121063*
X0043768Y0120439*
X0044122Y0119909*
X0044651Y0119556*
X0045276Y0119432*
X00459Y0119556*
X0046429Y0119909*
X0046783Y0120439*
X0046907Y0121063*
X0046783Y0121687*
X0046429Y0122216*
X00459Y012257*
X0045276Y0122694*
G37*
G36*
X0112205Y0118757D02*
X011158Y0118633D01*
X0111051Y011828*
X0110698Y011775*
X0110573Y0117126*
X0110698Y0116502*
X0111051Y0115972*
X011158Y0115619*
X0112205Y0115495*
X0112829Y0115619*
X0113358Y0115972*
X0113712Y0116502*
X0113836Y0117126*
X0113712Y011775*
X0113358Y011828*
X0112829Y0118633*
X0112205Y0118757*
G37*
G36*
X0282677Y0099269D02*
X0282053Y0099145D01*
X0281524Y0098791*
X0281075*
X0280546Y0099145*
X0279921Y0099269*
X0279297Y0099145*
X0278768Y0098791*
X0278647Y0098611*
X0278046*
X0277925Y0098791*
X0277396Y0099145*
X0276772Y0099269*
X0276147Y0099145*
X0275618Y0098791*
X0275169*
X027464Y0099145*
X0274016Y0099269*
X0273392Y0099145*
X0272862Y0098791*
X0272742Y0098611*
X027214*
X027202Y0098791*
X027149Y0099145*
X0270866Y0099269*
X0270242Y0099145*
X0269713Y0098791*
X0269264*
X0268735Y0099145*
X026811Y0099269*
X0267486Y0099145*
X0266957Y0098791*
X0266836Y0098611*
X0266235*
X0266114Y0098791*
X0265585Y0099145*
X0264961Y0099269*
X0264336Y0099145*
X0263807Y0098791*
X0263358*
X0262829Y0099145*
X0262205Y0099269*
X026158Y0099145*
X0261051Y0098791*
X0260698Y0098262*
X0260573Y0097638*
X0260698Y0097013*
X0261051Y0096484*
X026158Y0096131*
X0262205Y0096006*
X0262829Y0096131*
X0263358Y0096484*
X0263807*
X0264336Y0096131*
X0264961Y0096006*
X0265585Y0096131*
X0266114Y0096484*
X0266235Y0096665*
X0266836*
X0266957Y0096484*
X0267486Y0096131*
X026811Y0096006*
X0268735Y0096131*
X0269264Y0096484*
X0269713*
X0270242Y0096131*
X0270866Y0096006*
X027149Y0096131*
X027202Y0096484*
X027214Y0096665*
X0272742*
X0272862Y0096484*
X0273392Y0096131*
X0274016Y0096006*
X027464Y0096131*
X0275169Y0096484*
X0275618*
X0276147Y0096131*
X0276772Y0096006*
X0277396Y0096131*
X0277925Y0096484*
X0278046Y0096665*
X0278647*
X0278768Y0096484*
X0279297Y0096131*
X0279921Y0096006*
X0280546Y0096131*
X0281075Y0096484*
X0281524*
X0282053Y0096131*
X0282677Y0096006*
X0283301Y0096131*
X0283831Y0096484*
X0284184Y0097013*
X0284309Y0097638*
X0284184Y0098262*
X0283831Y0098791*
X0283301Y0099145*
X0282677Y0099269*
G37*
G36*
X0299015Y0097765D02*
X0298281Y0097619D01*
X0297658Y0097203*
X0297242Y009658*
X0297096Y0095846*
X0297242Y0095111*
X0297658Y0094488*
X0298281Y0094072*
X0299015Y0093926*
X029975Y0094072*
X0300373Y0094488*
X0300789Y0095111*
X0300935Y0095846*
X0300789Y009658*
X0300373Y0097203*
X029975Y0097619*
X0299015Y0097765*
G37*
G36*
X0220275D02*
X0219541Y0097619D01*
X0218918Y0097203*
X0218502Y009658*
X0218356Y0095846*
X0218502Y0095111*
X0218918Y0094488*
X0219541Y0094072*
X0220275Y0093926*
X022101Y0094072*
X0221633Y0094488*
X0222049Y0095111*
X0222195Y0095846*
X0222049Y009658*
X0221633Y0097203*
X022101Y0097619*
X0220275Y0097765*
G37*
G36*
X0119587Y0093068D02*
X0118962Y0092944D01*
X0118433Y009259*
X0118079Y0092061*
X0117955Y0091437*
X0118079Y0090813*
X0118433Y0090284*
X0118962Y008993*
X0119587Y0089806*
X0120211Y008993*
X012074Y0090284*
X0121094Y0090813*
X0121218Y0091437*
X0121094Y0092061*
X012074Y009259*
X0120211Y0092944*
X0119587Y0093068*
G37*
G36*
X0361755Y0098353D02*
X0360441Y0098224D01*
X0359177Y0097841*
X0358012Y0097218*
X0356991Y009638*
X0356153Y0095359*
X035553Y0094194*
X0355147Y009293*
X0355017Y0091615*
X0355147Y0090301*
X035553Y0089037*
X0356153Y0087872*
X0356991Y0086851*
X0358012Y0086013*
X0359177Y0085391*
X0360441Y0085007*
X0361755Y0084878*
X036307Y0085007*
X0364334Y0085391*
X0365499Y0086013*
X036652Y0086851*
X0367358Y0087872*
X0367981Y0089037*
X0368364Y0090301*
X0368493Y0091615*
X0368364Y009293*
X0367981Y0094194*
X0367358Y0095359*
X036652Y009638*
X0365499Y0097218*
X0364334Y0097841*
X036307Y0098224*
X0361755Y0098353*
G37*
G36*
X0165255D02*
X0163941Y0098224D01*
X0162677Y0097841*
X0161512Y0097218*
X0160491Y009638*
X0159653Y0095359*
X015903Y0094194*
X0158647Y009293*
X0158518Y0091615*
X0158647Y0090301*
X015903Y0089037*
X0159653Y0087872*
X0160491Y0086851*
X0161512Y0086013*
X0162677Y0085391*
X0163941Y0085007*
X0165255Y0084878*
X016657Y0085007*
X0167834Y0085391*
X0168999Y0086013*
X017002Y0086851*
X0170858Y0087872*
X0171481Y0089037*
X0171864Y0090301*
X0171993Y0091615*
X0171864Y009293*
X0171481Y0094194*
X0170858Y0095359*
X017002Y009638*
X0168999Y0097218*
X0167834Y0097841*
X016657Y0098224*
X0165255Y0098353*
G37*
G36*
X0019984Y0097037D02*
X001873Y0096914D01*
X0017523Y0096548*
X0016411Y0095954*
X0015437Y0095154*
X0014637Y0094179*
X0014043Y0093067*
X0013677Y0091861*
X0013553Y0090606*
X0013677Y0089352*
X0014043Y0088145*
X0014637Y0087033*
X0015437Y0086059*
X0016411Y0085259*
X0017523Y0084665*
X001873Y0084299*
X0019984Y0084175*
X0021239Y0084299*
X0022445Y0084665*
X0023557Y0085259*
X0024532Y0086059*
X0025331Y0087033*
X0025926Y0088145*
X0026292Y0089352*
X0026415Y0090606*
X0026292Y0091861*
X0025926Y0093067*
X0025331Y0094179*
X0024532Y0095154*
X0023557Y0095954*
X0022445Y0096548*
X0021239Y0096914*
X0019984Y0097037*
G37*
G36*
X055873Y0092581D02*
X0557543Y0092425D01*
X0556436Y0091966*
X0555485Y0091237*
X0554756Y0090287*
X0554297Y008918*
X0554141Y0087992*
X0554297Y0086804*
X0554756Y0085698*
X0555485Y0084747*
X0556436Y0084018*
X0557543Y0083559*
X055873Y0083403*
X0559918Y0083559*
X0561025Y0084018*
X0561975Y0084747*
X0562705Y0085698*
X0563163Y0086804*
X0563319Y0087992*
X0563163Y008918*
X0562705Y0090287*
X0561975Y0091237*
X0561025Y0091966*
X0559918Y0092425*
X055873Y0092581*
G37*
G36*
X0398888D02*
X03977Y0092425D01*
X0396593Y0091966*
X0395643Y0091237*
X0394913Y0090287*
X0394455Y008918*
X0394299Y0087992*
X0394455Y0086804*
X0394913Y0085698*
X0395643Y0084747*
X0396593Y0084018*
X03977Y0083559*
X0398888Y0083403*
X0400075Y0083559*
X0401182Y0084018*
X0402133Y0084747*
X0402862Y0085698*
X0403321Y0086804*
X0403477Y0087992*
X0403321Y008918*
X0402862Y0090287*
X0402133Y0091237*
X0401182Y0091966*
X0400075Y0092425*
X0398888Y0092581*
G37*
G36*
X0275984Y0081159D02*
X027536Y0081035D01*
X0274831Y0080681*
X0274382*
X0273853Y0081035*
X0273228Y0081159*
X0272604Y0081035*
X0272075Y0080681*
X0271721Y0080152*
X0271597Y0079528*
X0271721Y0078903*
X0272075Y0078374*
X0272604Y007802*
X0273228Y0077896*
X0273853Y007802*
X0274382Y0078374*
X0274831*
X027536Y007802*
X0275984Y0077896*
X0276608Y007802*
X0277138Y0078374*
X0277491Y0078903*
X0277616Y0079528*
X0277491Y0080152*
X0277138Y0080681*
X0276608Y0081035*
X0275984Y0081159*
G37*
G36*
X0269291D02*
X0268667Y0081035D01*
X0268138Y0080681*
X0267689*
X026716Y0081035*
X0266535Y0081159*
X0265911Y0081035*
X0265382Y0080681*
X0265028Y0080152*
X0264904Y0079528*
X0265028Y0078903*
X0265382Y0078374*
X0265911Y007802*
X0266535Y0077896*
X026716Y007802*
X0267689Y0078374*
X0268138*
X0268667Y007802*
X0269291Y0077896*
X0269916Y007802*
X0270445Y0078374*
X0270798Y0078903*
X0270923Y0079528*
X0270798Y0080152*
X0270445Y0080681*
X0269916Y0081035*
X0269291Y0081159*
G37*
G36*
X0262598D02*
X0261974Y0081035D01*
X0261445Y0080681*
X0260996*
X0260467Y0081035*
X0259842Y0081159*
X0259218Y0081035*
X0258689Y0080681*
X0258335Y0080152*
X0258211Y0079528*
X0258335Y0078903*
X0258689Y0078374*
X0259218Y007802*
X0259842Y0077896*
X0260467Y007802*
X0260996Y0078374*
X0261445*
X0261974Y007802*
X0262598Y0077896*
X0263223Y007802*
X0263752Y0078374*
X0264106Y0078903*
X026423Y0079528*
X0264106Y0080152*
X0263752Y0080681*
X0263223Y0081035*
X0262598Y0081159*
G37*
G36*
X028937D02*
X0288746Y0081035D01*
X0288216Y0080681*
X0288096Y0080501*
X0287495*
X0287374Y0080681*
X0286845Y0081035*
X0286221Y0081159*
X0285596Y0081035*
X0285067Y0080681*
X0284713Y0080152*
X0284704Y0080104*
X0284194*
X0284184Y0080152*
X0283831Y0080681*
X0283301Y0081035*
X0282677Y0081159*
X0282053Y0081035*
X0281524Y0080681*
X0281075*
X0280546Y0081035*
X0279921Y0081159*
X0279297Y0081035*
X0278768Y0080681*
X0278414Y0080152*
X027829Y0079528*
X0278414Y0078903*
X0278768Y0078374*
X0279297Y007802*
X0279921Y0077896*
X0280546Y007802*
X0281075Y0078374*
X0281524*
X0282053Y007802*
X0282677Y0077896*
X0283301Y007802*
X0283831Y0078374*
X0284184Y0078903*
X0284194Y0078951*
X0284704*
X0284713Y0078903*
X0285067Y0078374*
X0285596Y007802*
X0286221Y0077896*
X0286845Y007802*
X0287374Y0078374*
X0287495Y0078554*
X0288096*
X0288216Y0078374*
X0288746Y007802*
X028937Y0077896*
X0289994Y007802*
X0290524Y0078374*
X0290877Y0078903*
X0291001Y0079528*
X0290877Y0080152*
X0290524Y0080681*
X0289994Y0081035*
X028937Y0081159*
G37*
G36*
X0370669Y0076262D02*
X0369808Y0076148D01*
X0369005Y0075816*
X0368316Y0075287*
X0367787Y0074597*
X0367454Y0073795*
X0367341Y0072933*
X0367454Y0072072*
X0367787Y0071269*
X0368316Y0070579*
X0369005Y0070051*
X0369808Y0069718*
X0370669Y0069605*
X0371531Y0069718*
X0372334Y0070051*
X0373023Y0070579*
X0373552Y0071269*
X0373884Y0072072*
X0373998Y0072933*
X0373884Y0073795*
X0373552Y0074597*
X0373023Y0075287*
X0372334Y0075816*
X0371531Y0076148*
X0370669Y0076262*
G37*
G36*
X0213583Y0057734D02*
X0212958Y0057609D01*
X0212598Y0057369*
X0212239Y0057609*
X0211614Y0057734*
X021099Y0057609*
X021063Y0057369*
X021027Y0057609*
X0209646Y0057734*
X0209021Y0057609*
X0208492Y0057256*
X0208138Y0056727*
X0208014Y0056102*
X0208138Y0055478*
X0208379Y0055118*
X0208138Y0054758*
X0208014Y0054134*
X0208138Y005351*
X0208492Y005298*
X0209021Y0052627*
X0209646Y0052503*
X021027Y0052627*
X021063Y0052867*
X021099Y0052627*
X0211614Y0052503*
X0212239Y0052627*
X0212598Y0052867*
X0212958Y0052627*
X0213583Y0052503*
X0214207Y0052627*
X0214736Y005298*
X021509Y005351*
X0215214Y0054134*
X021509Y0054758*
X0214849Y0055118*
X021509Y0055478*
X0215214Y0056102*
X021509Y0056727*
X0214736Y0057256*
X0214207Y0057609*
X0213583Y0057734*
G37*
G36*
X0246988Y004273D02*
X0246364Y0042606D01*
X0245835Y0042252*
X0245481Y0041723*
X0245357Y0041099*
X0245481Y0040475*
X0245835Y0039945*
X0246364Y0039592*
X0246988Y0039467*
X0247613Y0039592*
X0248142Y0039945*
X0248495Y0040475*
X024862Y0041099*
X0248495Y0041723*
X0248142Y0042252*
X0247613Y0042606*
X0246988Y004273*
G37*
G36*
X0298046Y0042547D02*
X0297421Y0042423D01*
X0296892Y0042069*
X0296538Y004154*
X0296414Y0040915*
X0296538Y0040291*
X0296892Y0039762*
X0297421Y0039408*
X0298046Y0039284*
X029867Y0039408*
X0299199Y0039762*
X0299553Y0040291*
X0299677Y0040915*
X0299553Y004154*
X0299199Y0042069*
X029867Y0042423*
X0298046Y0042547*
G37*
G36*
X0301969Y0042182D02*
X0301344Y0042058D01*
X0300815Y0041705*
X0300461Y0041175*
X0300337Y0040551*
X0300461Y0039927*
X0300815Y0039398*
X0301344Y0039044*
X0301969Y003892*
X0302593Y0039044*
X0303122Y0039398*
X0303476Y0039927*
X03036Y0040551*
X0303476Y0041175*
X0303122Y0041705*
X0302593Y0042058*
X0301969Y0042182*
G37*
G36*
X0282198Y0042417D02*
X0281574Y0042292D01*
X0281045Y0041939*
X0280691Y004141*
X0280567Y0040785*
X0280691Y0040161*
X0281045Y0039632*
X0281574Y0039278*
X0282198Y0039154*
X0282823Y0039278*
X0283352Y0039632*
X028346Y0039793*
X0283528Y0039813*
X0284038Y0039759*
X0284279Y0039398*
X0284809Y0039044*
X0285433Y003892*
X0286057Y0039044*
X0286587Y0039398*
X028694Y0039927*
X0287064Y0040551*
X028694Y0041175*
X0286587Y0041705*
X0286057Y0042058*
X0285433Y0042182*
X0284809Y0042058*
X0284279Y0041705*
X0284172Y0041543*
X0284103Y0041524*
X0283593Y0041578*
X0283352Y0041939*
X0282823Y0042292*
X0282198Y0042417*
G37*
G36*
X0270472Y0042182D02*
X0269848Y0042058D01*
X0269319Y0041705*
X0268965Y0041175*
X0268841Y0040551*
X0268965Y0039927*
X0269319Y0039398*
X0269848Y0039044*
X0270472Y003892*
X0271097Y0039044*
X0271626Y0039398*
X027198Y0039927*
X0272104Y0040551*
X027198Y0041175*
X0271626Y0041705*
X0271097Y0042058*
X0270472Y0042182*
G37*
G36*
X0266535D02*
X0265911Y0042058D01*
X0265382Y0041705*
X0265028Y0041175*
X0264904Y0040551*
X0265028Y0039927*
X0265382Y0039398*
X0265911Y0039044*
X0266535Y003892*
X026716Y0039044*
X0267689Y0039398*
X0268043Y0039927*
X0268167Y0040551*
X0268043Y0041175*
X0267689Y0041705*
X026716Y0042058*
X0266535Y0042182*
G37*
G36*
X0251181D02*
X0250557Y0042058D01*
X0250028Y0041705*
X0249674Y0041175*
X024955Y0040551*
X0249674Y0039927*
X0250028Y0039398*
X0250557Y0039044*
X0251181Y003892*
X0251805Y0039044*
X0252335Y0039398*
X0252688Y0039927*
X0252812Y0040551*
X0252688Y0041175*
X0252335Y0041705*
X0251805Y0042058*
X0251181Y0042182*
G37*
G36*
X0238976D02*
X0238352Y0042058D01*
X0237823Y0041705*
X0237469Y0041175*
X0237345Y0040551*
X0237469Y0039927*
X0237823Y0039398*
X0238352Y0039044*
X0238976Y003892*
X0239601Y0039044*
X024013Y0039398*
X0240484Y0039927*
X0240608Y0040551*
X0240484Y0041175*
X024013Y0041705*
X0239601Y0042058*
X0238976Y0042182*
G37*
G36*
X0235039D02*
X0234415Y0042058D01*
X0233886Y0041705*
X0233532Y0041175*
X0233408Y0040551*
X0233532Y0039927*
X0233886Y0039398*
X0234415Y0039044*
X0235039Y003892*
X0235664Y0039044*
X0236193Y0039398*
X0236546Y0039927*
X0236671Y0040551*
X0236546Y0041175*
X0236193Y0041705*
X0235664Y0042058*
X0235039Y0042182*
G37*
G36*
X0207087Y0039427D02*
X0206462Y0039302D01*
X0205933Y0038949*
X0205579Y003842*
X0205455Y0037795*
X0205579Y0037171*
X0205933Y0036642*
X0206462Y0036288*
X0207087Y0036164*
X0207711Y0036288*
X020824Y0036642*
X0208594Y0037171*
X0208718Y0037795*
X0208594Y003842*
X020824Y0038949*
X0207711Y0039302*
X0207087Y0039427*
G37*
G36*
X0187205Y0030371D02*
X018658Y0030247D01*
X0186221Y0030007*
X0185861Y0030247*
X0185236Y0030371*
X0184612Y0030247*
X0184252Y0030007*
X0183892Y0030247*
X0183268Y0030371*
X0182643Y0030247*
X0182114Y0029894*
X0181761Y0029364*
X0181636Y002874*
X0181761Y0028116*
X0182114Y0027587*
X0182295Y0027466*
Y0026865*
X0182114Y0026744*
X0181761Y0026215*
X0181636Y0025591*
X0181761Y0024966*
X0182114Y0024437*
X0182643Y0024083*
X0183268Y0023959*
X0183892Y0024083*
X0184252Y0024324*
X0184612Y0024083*
X0185236Y0023959*
X0185861Y0024083*
X0186221Y0024324*
X018658Y0024083*
X0187205Y0023959*
X0187829Y0024083*
X0188358Y0024437*
X0188712Y0024966*
X0188836Y0025591*
X0188712Y0026215*
X0188358Y0026744*
X0188178Y0026865*
Y0027466*
X0188358Y0027587*
X0188712Y0028116*
X0188836Y002874*
X0188712Y0029364*
X0188358Y0029894*
X0187829Y0030247*
X0187205Y0030371*
G37*
G36*
X0211221D02*
X0210596Y0030247D01*
X0210067Y0029894*
X0209713Y0029364*
X0209704Y0029316*
X0209194*
X0209184Y0029364*
X0208831Y0029894*
X0208301Y0030247*
X0207677Y0030371*
X0207053Y0030247*
X0206524Y0029894*
X020617Y0029364*
X0206046Y002874*
X020617Y0028116*
X0206524Y0027587*
X0206704Y0027466*
Y0026865*
X0206524Y0026744*
X020617Y0026215*
X0206046Y0025591*
X020617Y0024966*
X0206524Y0024437*
X0207053Y0024083*
X0207677Y0023959*
X0208301Y0024083*
X0208831Y0024437*
X0209184Y0024966*
X0209194Y0025014*
X0209704*
X0209713Y0024966*
X0210067Y0024437*
X0210596Y0024083*
X0211221Y0023959*
X0211845Y0024083*
X0212374Y0024437*
X0212728Y0024966*
X0212852Y0025591*
X0212728Y0026215*
X0212374Y0026744*
X0212193Y0026865*
Y0027466*
X0212374Y0027587*
X0212728Y0028116*
X0212852Y002874*
X0212728Y0029364*
X0212374Y0029894*
X0211845Y0030247*
X0211221Y0030371*
G37*
G36*
X0261024Y0029584D02*
X0260399Y002946D01*
X025987Y0029106*
X025975Y0028926*
X0259148*
X0259028Y0029106*
X0258498Y002946*
X0257874Y0029584*
X025725Y002946*
X025672Y0029106*
X0256367Y0028577*
X0256243Y0027953*
X0256367Y0027329*
X025672Y0026799*
X025725Y0026446*
X0257874Y0026321*
X0258498Y0026446*
X0259028Y0026799*
X0259148Y002698*
X025975*
X025987Y0026799*
X0260399Y0026446*
X0261024Y0026321*
X0261648Y0026446*
X0262177Y0026799*
X0262531Y0027329*
X0262655Y0027953*
X0262531Y0028577*
X0262177Y0029106*
X0261648Y002946*
X0261024Y0029584*
G37*
G36*
X0244488D02*
X0243864Y002946D01*
X0243335Y0029106*
X0243214Y0028926*
X0242613*
X0242492Y0029106*
X0241963Y002946*
X0241339Y0029584*
X0240714Y002946*
X0240185Y0029106*
X0239831Y0028577*
X0239707Y0027953*
X0239831Y0027329*
X0240185Y0026799*
X0240714Y0026446*
X0241339Y0026321*
X0241963Y0026446*
X0242492Y0026799*
X0242613Y002698*
X0243214*
X0243335Y0026799*
X0243864Y0026446*
X0244488Y0026321*
X0245112Y0026446*
X0245642Y0026799*
X0245995Y0027329*
X0246119Y0027953*
X0245995Y0028577*
X0245642Y0029106*
X0245112Y002946*
X0244488Y0029584*
G37*
G36*
X0293701D02*
X0293076Y002946D01*
X0292547Y0029106*
X0292425Y0028924*
X0291824*
X0291703Y0029105*
X0291174Y0029458*
X0290549Y0029582*
X0289925Y0029458*
X0289396Y0029105*
X0289042Y0028575*
X0288918Y0027951*
X0289042Y0027327*
X0289396Y0026798*
X0289925Y0026444*
X0290549Y002632*
X0291174Y0026444*
X0291703Y0026798*
X0291825Y002698*
X0292426*
X0292547Y0026799*
X0293076Y0026446*
X0293701Y0026321*
X0294325Y0026446*
X0294854Y0026799*
X0295208Y0027329*
X0295332Y0027953*
X0295208Y0028577*
X0294854Y0029106*
X0294325Y002946*
X0293701Y0029584*
G37*
G36*
X0274882Y0029862D02*
X0274258Y0029738D01*
X0273728Y0029385*
X0273375Y0028855*
X0273251Y0028231*
X0273375Y0027607*
X0273728Y0027078*
X0274258Y0026724*
X0274882Y00266*
X0275506Y0026724*
X0276035Y0027078*
X0276625Y002706*
X0276799Y0026799*
X0277328Y0026446*
X0277953Y0026321*
X0278577Y0026446*
X0279106Y0026799*
X027946Y0027329*
X0279584Y0027953*
X027946Y0028577*
X0279106Y0029106*
X0278577Y002946*
X0277953Y0029584*
X0277328Y002946*
X0276799Y0029106*
X027621Y0029124*
X0276035Y0029385*
X0275506Y0029738*
X0274882Y0029862*
G37*
G36*
X0215158Y0030371D02*
X0214533Y0030247D01*
X0214004Y0029894*
X021365Y0029364*
X0213526Y002874*
X021365Y0028116*
X0214004Y0027587*
X0214184Y0027466*
Y0026865*
X0214004Y0026744*
X021365Y0026215*
X0213526Y0025591*
X021365Y0024966*
X0214004Y0024437*
X0214533Y0024083*
X0215158Y0023959*
X0215782Y0024083*
X0216311Y0024437*
X0216665Y0024966*
X0216789Y0025591*
X0216665Y0026215*
X0216311Y0026744*
X021613Y0026865*
Y0027466*
X0216311Y0027587*
X0216665Y0028116*
X0216789Y002874*
X0216665Y0029364*
X0216311Y0029894*
X0215782Y0030247*
X0215158Y0030371*
G37*
G36*
X0028543Y0050152D02*
X0026456Y0049988D01*
X0024421Y0049499*
X0022487Y0048698*
X0020702Y0047604*
X001911Y0046245*
X001775Y0044653*
X0016656Y0042868*
X0015855Y0040934*
X0015366Y0038898*
X0015202Y0036811*
X0015366Y0034724*
X0015855Y0032688*
X0016656Y0030754*
X001775Y0028969*
X001911Y0027377*
X0020702Y0026018*
X0022487Y0024924*
X0024421Y0024123*
X0026456Y0023634*
X0028543Y002347*
X003063Y0023634*
X0032666Y0024123*
X00346Y0024924*
X0036385Y0026018*
X0037977Y0027377*
X0039336Y0028969*
X004043Y0030754*
X0041232Y0032688*
X004172Y0034724*
X0041884Y0036811*
X004172Y0038898*
X0041232Y0040934*
X004043Y0042868*
X0039336Y0044653*
X0037977Y0046245*
X0036385Y0047604*
X00346Y0048698*
X0032666Y0049499*
X003063Y0049988*
X0028543Y0050152*
G37*
%LNtimecard-dc-beta-v1-3*%
%LPD*%
G54D108*
X0009984Y0258106D03*
Y0238106D03*
X0029984D03*
Y0258106D03*
X0009984Y0100606D03*
Y0080606D03*
X0029984D03*
Y0100606D03*
X0009984Y0153106D03*
Y0133106D03*
X0029984D03*
Y0153106D03*
X0009984Y0205606D03*
Y0185606D03*
X0029984D03*
Y0205606D03*
G54D120*
X0398888Y0247835D03*
X055873Y0167913D03*
G54D121*
X0513622Y0426181D03*
G54D126*
X0045276Y0112205D03*
X004626Y0218504D03*
X0052689Y0207306D03*
X0101378Y0161417D03*
X0270669Y0309087D03*
X0261811Y0309055D03*
X0356299Y0303118D03*
X0366142D03*
X025889Y0242126D03*
X0525591Y0271654D03*
X0512795Y0279528D03*
Y028248D03*
X0519685Y0298228D03*
X0490158Y0270638D03*
X0505905Y0283465D03*
X0279528Y0284449D03*
X0202756Y0409449D03*
X0302165Y0332677D03*
X0286417Y0327756D03*
X0288059Y0241869D03*
X0240158Y0242126D03*
X0160433Y0409449D03*
X0217488Y0357695D03*
X0201772Y0076772D03*
X0216535Y0068898D03*
X0311024Y0281496D03*
Y0283465D03*
Y0285433D03*
X0331693Y0269685D03*
X0343504D03*
X0357185Y0272736D03*
X0290158Y011063D03*
X0285039D03*
X027874D03*
X0272835D03*
X0191614Y0024476D03*
X0627559Y0295276D03*
X0612992Y0276772D03*
X0271654Y0362205D03*
X0101181Y0110433D03*
X011811Y0184055D03*
Y0237205D03*
X0120079Y0200787D03*
Y0253937D03*
X0163957Y035748D03*
X0181727D03*
X0199803Y0357283D03*
X0288059Y0246457D03*
X025889D03*
X0229035Y0246555D03*
X0354331Y0171291D03*
X0360236D03*
X0268437Y0241831D03*
X0268701Y0246457D03*
X0354331Y0141732D03*
X0360236D03*
Y0151575D03*
X0354331D03*
Y0161417D03*
X0360236D03*
X0354331Y0181102D03*
X0360236D03*
X0354331Y0190945D03*
X0360236D03*
Y0200787D03*
X0354331D03*
X0167484Y0198906D03*
X0278248Y0241831D03*
X0248819D03*
X023002Y024187D03*
X0278543Y0246457D03*
X0239173D03*
X024941D03*
X0397899Y0165616D03*
X0401575Y0168307D03*
X0401533Y0172321D03*
X0171884Y0149606D03*
X0167184D03*
X0697884Y0183071D03*
X0231496Y0093307D03*
X0241339D03*
X0251575D03*
X0290551Y0093701D03*
X0266535Y011063D03*
X0261024D03*
X0251181Y0110591D03*
X0240945Y011063D03*
X0231102D03*
X0172184Y0168571D03*
X0167084D03*
X0636221Y0295276D03*
X0645084Y0246263D03*
Y0253543D03*
X0645276Y026063D03*
X0645182Y0267323D03*
X0645084Y0274016D03*
X065878Y0152931D03*
X0659449Y0167323D03*
Y0161024D03*
Y0177559D03*
Y0172047D03*
X0349705Y0064173D03*
X0171484Y0159506D03*
X0260668Y009319D03*
X0171884Y0179206D03*
X0167584Y0189106D03*
X0167184Y0179206D03*
Y0139906D03*
X0167084Y0159506D03*
X0171684Y0139906D03*
X0172184Y0198906D03*
Y0189006D03*
X0287828Y002496D03*
X0295747Y0025197D03*
X0244706Y0024259D03*
X0263687Y0024791D03*
X0279999Y0025197D03*
X0254606Y0024484D03*
X0309744Y0025197D03*
X0203484Y0024606D03*
X0230984D03*
X0662884Y0137206D03*
X0349853Y0068206D03*
X0669478Y018309D03*
X0669984Y0188106D03*
X0694984Y0209506D03*
X0660784Y0217606D03*
X0639584Y0211106D03*
X0604884Y0217106D03*
X0600394Y0243021D03*
X0627484Y0239106D03*
X0052689Y0079006D03*
X0052789Y0102806D03*
X0052689Y0131406D03*
X0052589Y0155106D03*
X0052689Y0183906D03*
Y0236506D03*
X0052601Y0259389D03*
M02*